G04 ================== begin FILE IDENTIFICATION RECORD ==================*
G04 Layout Name:  16368-sb.brd*
G04 Film Name:    SE_REF_L6*
G04 File Format:  Gerber RS274X*
G04 File Origin:  Cadence Allegro 16.5-S056*
G04 Origin Date:  Tue Feb 07 09:07:46 2017*
G04 *
G04 Layer:  BOARD GEOMETRY/SE_REF_L6_TBL*
G04 Layer:  BOARD GEOMETRY/SE_REF_L6_BOTTOM*
G04 Layer:  BOARD GEOMETRY/PANEL_OUTLINE*
G04 *
G04 Offset:    (0.00 0.00)*
G04 Mirror:    No*
G04 Mode:      Positive*
G04 Rotation:  0*
G04 FullContactRelief:  No*
G04 UndefLineWidth:     6.00*
G04 ================== end FILE IDENTIFICATION RECORD ====================*
%FSLAX35Y35*MOIN*%
%IR0*IPPOS*OFA0.00000B0.00000*MIA0B0*SFA1.00000B1.00000*%
%ADD10C,.02*%
%ADD11C,.006*%
%ADD12C,.007*%
G75*
%LPD*%
G75*
G54D10*
G01X597544Y585326D02*
X1315044D01*
G01X597544Y654626D02*
Y585326D01*
G01Y654626D02*
X1315044D01*
G01X597544Y619976D02*
X1315044D01*
G01X772544Y654626D02*
Y585326D01*
G01X1000044Y654626D02*
Y585326D01*
G01X1105044Y654626D02*
Y585326D01*
G01X1315044Y654626D02*
Y585326D01*
G54D11*
G01X6250Y-52485D02*
Y-69985D01*
G01X1228Y-52485D02*
X11272D01*
G01X20038Y-69985D02*
Y-52485D01*
G01Y-60943D02*
X21130Y-59485D01*
X22222Y-58610D01*
X23968Y-58319D01*
X25278Y-58610D01*
X26807Y-59777D01*
X27462Y-61527D01*
Y-69985D01*
G01X41250Y-58319D02*
Y-69985D01*
G01Y-53652D02*
X40813Y-53360D01*
Y-52777D01*
X41250Y-52485D01*
X41687Y-52777D01*
Y-53360D01*
X41250Y-53652D01*
G01X55475Y-67944D02*
X56567Y-69110D01*
X58095Y-69985D01*
X59405D01*
X60715Y-69402D01*
X61588Y-68527D01*
X62025Y-67361D01*
X61807Y-65610D01*
X60933Y-64735D01*
X57003Y-62985D01*
X56130Y-60943D01*
X56567Y-59485D01*
X57440Y-58610D01*
X58750Y-58319D01*
X60060Y-58610D01*
X61370Y-59485D01*
G01X90693Y-74360D02*
X92222Y-75527D01*
X93968Y-75818D01*
X95496Y-75527D01*
X96807Y-74069D01*
X97680Y-72027D01*
Y-58319D01*
G01Y-60652D02*
X96807Y-59485D01*
X95496Y-58610D01*
X93968Y-58319D01*
X92222Y-58902D01*
X91130Y-60068D01*
X90256Y-62110D01*
X89820Y-64152D01*
X90038Y-65902D01*
X90912Y-67944D01*
X92222Y-69402D01*
X93968Y-69985D01*
X95278Y-69693D01*
X96807Y-68527D01*
X97680Y-67361D01*
G01X107975Y-62110D02*
X114962D01*
X114307Y-60068D01*
X113215Y-58902D01*
X111687Y-58319D01*
X110158Y-58610D01*
X108848Y-59485D01*
X107975Y-61527D01*
X107538Y-63277D01*
Y-65027D01*
X107975Y-66777D01*
X109067Y-68527D01*
X110377Y-69693D01*
X111905Y-69985D01*
X113433Y-69402D01*
X114962Y-67652D01*
G01X125693Y-69985D02*
Y-58319D01*
G01Y-60652D02*
X126785Y-59485D01*
X127877Y-58610D01*
X129405Y-58319D01*
X130496Y-58610D01*
X131807Y-59485D01*
G01X142320Y-69985D02*
Y-52485D01*
G01Y-61235D02*
X143412Y-59485D01*
X144722Y-58610D01*
X146032Y-58319D01*
X147996Y-58902D01*
X149307Y-60068D01*
X150180Y-62110D01*
Y-64443D01*
X149743Y-66777D01*
X148870Y-68527D01*
X147342Y-69693D01*
X146032Y-69985D01*
X144722Y-69693D01*
X143412Y-68819D01*
X142320Y-67361D01*
G01X160475Y-62110D02*
X167462D01*
X166807Y-60068D01*
X165715Y-58902D01*
X164187Y-58319D01*
X162658Y-58610D01*
X161348Y-59485D01*
X160475Y-61527D01*
X160038Y-63277D01*
Y-65027D01*
X160475Y-66777D01*
X161567Y-68527D01*
X162877Y-69693D01*
X164405Y-69985D01*
X165933Y-69402D01*
X167462Y-67652D01*
G01X178193Y-69985D02*
Y-58319D01*
G01Y-60652D02*
X179285Y-59485D01*
X180377Y-58610D01*
X181905Y-58319D01*
X182996Y-58610D01*
X184307Y-59485D01*
G01X216250Y-58319D02*
Y-69985D01*
G01Y-53652D02*
X215813Y-53360D01*
Y-52777D01*
X216250Y-52485D01*
X216687Y-52777D01*
Y-53360D01*
X216250Y-53652D01*
G01X230475Y-67944D02*
X231567Y-69110D01*
X233095Y-69985D01*
X234405D01*
X235715Y-69402D01*
X236588Y-68527D01*
X237025Y-67361D01*
X236807Y-65610D01*
X235933Y-64735D01*
X232003Y-62985D01*
X231130Y-60943D01*
X231567Y-59485D01*
X232440Y-58610D01*
X233750Y-58319D01*
X235060Y-58610D01*
X236370Y-59485D01*
G01X265256Y-74360D02*
X266785Y-75527D01*
X268095Y-75818D01*
X269842Y-75235D01*
X271152Y-73777D01*
X271807Y-71151D01*
Y-58319D01*
G01Y-53652D02*
X271370Y-53360D01*
Y-52777D01*
X271807Y-52485D01*
X272243Y-52777D01*
Y-53360D01*
X271807Y-53652D01*
G01X282538Y-58319D02*
Y-66485D01*
X283412Y-68527D01*
X284722Y-69693D01*
X286250Y-69985D01*
X287778Y-69693D01*
X289088Y-68527D01*
X289962Y-66485D01*
G01Y-69985D02*
Y-58319D01*
G01X300475Y-67944D02*
X301567Y-69110D01*
X303095Y-69985D01*
X304405D01*
X305715Y-69402D01*
X306588Y-68527D01*
X307025Y-67361D01*
X306807Y-65610D01*
X305933Y-64735D01*
X302003Y-62985D01*
X301130Y-60943D01*
X301567Y-59485D01*
X302440Y-58610D01*
X303750Y-58319D01*
X305060Y-58610D01*
X306370Y-59485D01*
G01X321250Y-52485D02*
Y-69985D01*
G01X318193Y-58319D02*
X324307D01*
G01X354940Y-69985D02*
Y-55110D01*
X355377Y-53652D01*
X356250Y-52777D01*
X357560Y-52485D01*
X358870Y-53068D01*
X359525Y-54527D01*
G01X356905Y-59485D02*
X352538D01*
G01X373750Y-69985D02*
X372440Y-69693D01*
X371130Y-68527D01*
X370256Y-66485D01*
X369820Y-64152D01*
X370256Y-61818D01*
X371130Y-59777D01*
X372440Y-58610D01*
X373750Y-58319D01*
X375060Y-58610D01*
X376370Y-59777D01*
X377243Y-61818D01*
X377462Y-64152D01*
X377243Y-66485D01*
X376370Y-68527D01*
X375060Y-69693D01*
X373750Y-69985D01*
G01X388193D02*
Y-58319D01*
G01Y-60652D02*
X389285Y-59485D01*
X390377Y-58610D01*
X391905Y-58319D01*
X392996Y-58610D01*
X394307Y-59485D01*
G01X421665Y-75235D02*
X422975Y-75818D01*
X424722Y-75235D01*
X425813Y-74069D01*
X426687Y-72610D01*
X427996Y-67944D01*
X430835Y-58319D01*
G01X423848D02*
X427996Y-67944D01*
G01X443750Y-69985D02*
X442440Y-69693D01*
X441130Y-68527D01*
X440256Y-66485D01*
X439820Y-64152D01*
X440256Y-61818D01*
X441130Y-59777D01*
X442440Y-58610D01*
X443750Y-58319D01*
X445060Y-58610D01*
X446370Y-59777D01*
X447243Y-61818D01*
X447462Y-64152D01*
X447243Y-66485D01*
X446370Y-68527D01*
X445060Y-69693D01*
X443750Y-69985D01*
G01X457538Y-58319D02*
Y-66485D01*
X458412Y-68527D01*
X459722Y-69693D01*
X461250Y-69985D01*
X462778Y-69693D01*
X464088Y-68527D01*
X464962Y-66485D01*
G01Y-69985D02*
Y-58319D01*
G01X475693Y-69985D02*
Y-58319D01*
G01Y-60652D02*
X476785Y-59485D01*
X477877Y-58610D01*
X479405Y-58319D01*
X480496Y-58610D01*
X481807Y-59485D01*
G01X510693Y-69985D02*
Y-58319D01*
G01Y-60652D02*
X511785Y-59485D01*
X512877Y-58610D01*
X514405Y-58319D01*
X515496Y-58610D01*
X516807Y-59485D01*
G01X527975Y-62110D02*
X534962D01*
X534307Y-60068D01*
X533215Y-58902D01*
X531687Y-58319D01*
X530158Y-58610D01*
X528848Y-59485D01*
X527975Y-61527D01*
X527538Y-63277D01*
Y-65027D01*
X527975Y-66777D01*
X529067Y-68527D01*
X530377Y-69693D01*
X531905Y-69985D01*
X533433Y-69402D01*
X534962Y-67652D01*
G01X547440Y-69985D02*
Y-55110D01*
X547877Y-53652D01*
X548750Y-52777D01*
X550060Y-52485D01*
X551370Y-53068D01*
X552025Y-54527D01*
G01X549405Y-59485D02*
X545038D01*
G01X562975Y-62110D02*
X569962D01*
X569307Y-60068D01*
X568215Y-58902D01*
X566687Y-58319D01*
X565158Y-58610D01*
X563848Y-59485D01*
X562975Y-61527D01*
X562538Y-63277D01*
Y-65027D01*
X562975Y-66777D01*
X564067Y-68527D01*
X565377Y-69693D01*
X566905Y-69985D01*
X568433Y-69402D01*
X569962Y-67652D01*
G01X580693Y-69985D02*
Y-58319D01*
G01Y-60652D02*
X581785Y-59485D01*
X582877Y-58610D01*
X584405Y-58319D01*
X585496Y-58610D01*
X586807Y-59485D01*
G01X597975Y-62110D02*
X604962D01*
X604307Y-60068D01*
X603215Y-58902D01*
X601687Y-58319D01*
X600158Y-58610D01*
X598848Y-59485D01*
X597975Y-61527D01*
X597538Y-63277D01*
Y-65027D01*
X597975Y-66777D01*
X599067Y-68527D01*
X600377Y-69693D01*
X601905Y-69985D01*
X603433Y-69402D01*
X604962Y-67652D01*
G01X615038Y-69985D02*
Y-58319D01*
G01Y-61235D02*
X615912Y-59777D01*
X617222Y-58610D01*
X618968Y-58319D01*
X620496Y-58610D01*
X621807Y-59777D01*
X622462Y-61818D01*
Y-69985D01*
G01X639743Y-59777D02*
X638215Y-58610D01*
X636905Y-58319D01*
X635158Y-58902D01*
X633848Y-60068D01*
X632975Y-62110D01*
X632756Y-64152D01*
X632975Y-66194D01*
X633848Y-67944D01*
X635158Y-69402D01*
X636905Y-69985D01*
X638433Y-69402D01*
X639743Y-68235D01*
G01X650475Y-62110D02*
X657462D01*
X656807Y-60068D01*
X655715Y-58902D01*
X654187Y-58319D01*
X652658Y-58610D01*
X651348Y-59485D01*
X650475Y-61527D01*
X650038Y-63277D01*
Y-65027D01*
X650475Y-66777D01*
X651567Y-68527D01*
X652877Y-69693D01*
X654405Y-69985D01*
X655933Y-69402D01*
X657462Y-67652D01*
G01X688750Y-52485D02*
Y-69985D01*
G01X685693Y-58319D02*
X691807D01*
G01X706250Y-69985D02*
X704940Y-69693D01*
X703630Y-68527D01*
X702756Y-66485D01*
X702320Y-64152D01*
X702756Y-61818D01*
X703630Y-59777D01*
X704940Y-58610D01*
X706250Y-58319D01*
X707560Y-58610D01*
X708870Y-59777D01*
X709743Y-61818D01*
X709962Y-64152D01*
X709743Y-66485D01*
X708870Y-68527D01*
X707560Y-69693D01*
X706250Y-69985D01*
G01X739940D02*
Y-55110D01*
X740377Y-53652D01*
X741250Y-52777D01*
X742560Y-52485D01*
X743870Y-53068D01*
X744525Y-54527D01*
G01X741905Y-59485D02*
X737538D01*
G01X758750Y-58319D02*
Y-69985D01*
G01Y-53652D02*
X758313Y-53360D01*
Y-52777D01*
X758750Y-52485D01*
X759187Y-52777D01*
Y-53360D01*
X758750Y-53652D01*
G01X772538Y-69985D02*
Y-58319D01*
G01Y-61235D02*
X773412Y-59777D01*
X774722Y-58610D01*
X776468Y-58319D01*
X777996Y-58610D01*
X779307Y-59777D01*
X779962Y-61818D01*
Y-69985D01*
G01X797680Y-52485D02*
Y-69985D01*
G01Y-67361D02*
X796807Y-68819D01*
X795496Y-69693D01*
X793968Y-69985D01*
X792222Y-69402D01*
X790912Y-67944D01*
X790038Y-66194D01*
X789820Y-64152D01*
X790038Y-62110D01*
X790912Y-60360D01*
X792222Y-58902D01*
X793968Y-58319D01*
X795496Y-58610D01*
X796588Y-59194D01*
X797680Y-60360D01*
G01X828750Y-52485D02*
Y-69985D01*
G01X825693Y-58319D02*
X831807D01*
G01X842538Y-69985D02*
Y-52485D01*
G01Y-60943D02*
X843630Y-59485D01*
X844722Y-58610D01*
X846468Y-58319D01*
X847778Y-58610D01*
X849307Y-59777D01*
X849962Y-61527D01*
Y-69985D01*
G01X860475Y-62110D02*
X867462D01*
X866807Y-60068D01*
X865715Y-58902D01*
X864187Y-58319D01*
X862658Y-58610D01*
X861348Y-59485D01*
X860475Y-61527D01*
X860038Y-63277D01*
Y-65027D01*
X860475Y-66777D01*
X861567Y-68527D01*
X862877Y-69693D01*
X864405Y-69985D01*
X865933Y-69402D01*
X867462Y-67652D01*
G01X894165D02*
X895912Y-69110D01*
X897877Y-69985D01*
X899623D01*
X901370Y-69110D01*
X902680Y-67652D01*
X903335Y-65610D01*
X902898Y-63569D01*
X901807Y-61818D01*
X899842Y-60652D01*
X897222Y-60068D01*
X895693Y-58902D01*
X895038Y-56860D01*
X895475Y-54818D01*
X896567Y-53360D01*
X898095Y-52485D01*
X899623D01*
X901152Y-53068D01*
X902462Y-54527D01*
G01X920617Y-69985D02*
X911883D01*
Y-52485D01*
X920617D01*
G01X917123Y-60943D02*
X911883D01*
G01X951250Y-58319D02*
Y-69985D01*
G01Y-53652D02*
X950813Y-53360D01*
Y-52777D01*
X951250Y-52485D01*
X951687Y-52777D01*
Y-53360D01*
X951250Y-53652D01*
G01X962200Y-69985D02*
Y-58319D01*
G01Y-61527D02*
X962855Y-60068D01*
X963947Y-58902D01*
X965475Y-58319D01*
X967003Y-58902D01*
X968095Y-60068D01*
X968750Y-61527D01*
Y-69985D01*
G01Y-61527D02*
X969405Y-60068D01*
X970496Y-58902D01*
X972025Y-58319D01*
X973553Y-58902D01*
X974645Y-60068D01*
X975300Y-61818D01*
Y-69985D01*
G01X982320Y-75818D02*
Y-58319D01*
G01Y-60943D02*
X983412Y-59485D01*
X984503Y-58610D01*
X986250Y-58319D01*
X987778Y-58610D01*
X989307Y-60068D01*
X989962Y-62110D01*
X990180Y-64152D01*
X989962Y-66194D01*
X989307Y-68235D01*
X987996Y-69402D01*
X986250Y-69985D01*
X984722Y-69693D01*
X983193Y-68819D01*
X982320Y-67652D01*
G01X1000475Y-62110D02*
X1007462D01*
X1006807Y-60068D01*
X1005715Y-58902D01*
X1004187Y-58319D01*
X1002658Y-58610D01*
X1001348Y-59485D01*
X1000475Y-61527D01*
X1000038Y-63277D01*
Y-65027D01*
X1000475Y-66777D01*
X1001567Y-68527D01*
X1002877Y-69693D01*
X1004405Y-69985D01*
X1005933Y-69402D01*
X1007462Y-67652D01*
G01X1025180Y-52485D02*
Y-69985D01*
G01Y-67361D02*
X1024307Y-68819D01*
X1022996Y-69693D01*
X1021468Y-69985D01*
X1019722Y-69402D01*
X1018412Y-67944D01*
X1017538Y-66194D01*
X1017320Y-64152D01*
X1017538Y-62110D01*
X1018412Y-60360D01*
X1019722Y-58902D01*
X1021468Y-58319D01*
X1022996Y-58610D01*
X1024088Y-59194D01*
X1025180Y-60360D01*
G01X1042680Y-69985D02*
Y-58319D01*
G01Y-60360D02*
X1041807Y-59194D01*
X1040496Y-58610D01*
X1038968Y-58319D01*
X1037440Y-58902D01*
X1036130Y-60068D01*
X1035256Y-61818D01*
X1034820Y-64152D01*
X1035256Y-66485D01*
X1036130Y-68235D01*
X1037440Y-69402D01*
X1038968Y-69985D01*
X1040496Y-69693D01*
X1041807Y-68819D01*
X1042680Y-67652D01*
G01X1052538Y-69985D02*
Y-58319D01*
G01Y-61235D02*
X1053412Y-59777D01*
X1054722Y-58610D01*
X1056468Y-58319D01*
X1057996Y-58610D01*
X1059307Y-59777D01*
X1059962Y-61818D01*
Y-69985D01*
G01X1077243Y-59777D02*
X1075715Y-58610D01*
X1074405Y-58319D01*
X1072658Y-58902D01*
X1071348Y-60068D01*
X1070475Y-62110D01*
X1070256Y-64152D01*
X1070475Y-66194D01*
X1071348Y-67944D01*
X1072658Y-69402D01*
X1074405Y-69985D01*
X1075933Y-69402D01*
X1077243Y-68235D01*
G01X1087975Y-62110D02*
X1094962D01*
X1094307Y-60068D01*
X1093215Y-58902D01*
X1091687Y-58319D01*
X1090158Y-58610D01*
X1088848Y-59485D01*
X1087975Y-61527D01*
X1087538Y-63277D01*
Y-65027D01*
X1087975Y-66777D01*
X1089067Y-68527D01*
X1090377Y-69693D01*
X1091905Y-69985D01*
X1093433Y-69402D01*
X1094962Y-67652D01*
G01X1126250Y-52485D02*
Y-69985D01*
G01X1123193Y-58319D02*
X1129307D01*
G01X1140693Y-69985D02*
Y-58319D01*
G01Y-60652D02*
X1141785Y-59485D01*
X1142877Y-58610D01*
X1144405Y-58319D01*
X1145496Y-58610D01*
X1146807Y-59485D01*
G01X1165180Y-69985D02*
Y-58319D01*
G01Y-60360D02*
X1164307Y-59194D01*
X1162996Y-58610D01*
X1161468Y-58319D01*
X1159940Y-58902D01*
X1158630Y-60068D01*
X1157756Y-61818D01*
X1157320Y-64152D01*
X1157756Y-66485D01*
X1158630Y-68235D01*
X1159940Y-69402D01*
X1161468Y-69985D01*
X1162996Y-69693D01*
X1164307Y-68819D01*
X1165180Y-67652D01*
G01X1182243Y-59777D02*
X1180715Y-58610D01*
X1179405Y-58319D01*
X1177658Y-58902D01*
X1176348Y-60068D01*
X1175475Y-62110D01*
X1175256Y-64152D01*
X1175475Y-66194D01*
X1176348Y-67944D01*
X1177658Y-69402D01*
X1179405Y-69985D01*
X1180933Y-69402D01*
X1182243Y-68235D01*
G01X1192975Y-62110D02*
X1199962D01*
X1199307Y-60068D01*
X1198215Y-58902D01*
X1196687Y-58319D01*
X1195158Y-58610D01*
X1193848Y-59485D01*
X1192975Y-61527D01*
X1192538Y-63277D01*
Y-65027D01*
X1192975Y-66777D01*
X1194067Y-68527D01*
X1195377Y-69693D01*
X1196905Y-69985D01*
X1198433Y-69402D01*
X1199962Y-67652D01*
G01X1210475Y-67944D02*
X1211567Y-69110D01*
X1213095Y-69985D01*
X1214405D01*
X1215715Y-69402D01*
X1216588Y-68527D01*
X1217025Y-67361D01*
X1216807Y-65610D01*
X1215933Y-64735D01*
X1212003Y-62985D01*
X1211130Y-60943D01*
X1211567Y-59485D01*
X1212440Y-58610D01*
X1213750Y-58319D01*
X1215060Y-58610D01*
X1216370Y-59485D01*
G01X1248750Y-58319D02*
Y-69985D01*
G01Y-53652D02*
X1248313Y-53360D01*
Y-52777D01*
X1248750Y-52485D01*
X1249187Y-52777D01*
Y-53360D01*
X1248750Y-53652D01*
G01X1262538Y-69985D02*
Y-58319D01*
G01Y-61235D02*
X1263412Y-59777D01*
X1264722Y-58610D01*
X1266468Y-58319D01*
X1267996Y-58610D01*
X1269307Y-59777D01*
X1269962Y-61818D01*
Y-69985D01*
G01X1301250D02*
Y-52485D01*
G01X1322680Y-69985D02*
Y-58319D01*
G01Y-60360D02*
X1321807Y-59194D01*
X1320496Y-58610D01*
X1318968Y-58319D01*
X1317440Y-58902D01*
X1316130Y-60068D01*
X1315256Y-61818D01*
X1314820Y-64152D01*
X1315256Y-66485D01*
X1316130Y-68235D01*
X1317440Y-69402D01*
X1318968Y-69985D01*
X1320496Y-69693D01*
X1321807Y-68819D01*
X1322680Y-67652D01*
G01X1331665Y-75235D02*
X1332975Y-75818D01*
X1334722Y-75235D01*
X1335813Y-74069D01*
X1336687Y-72610D01*
X1337996Y-67944D01*
X1340835Y-58319D01*
G01X1333848D02*
X1337996Y-67944D01*
G01X1350475Y-62110D02*
X1357462D01*
X1356807Y-60068D01*
X1355715Y-58902D01*
X1354187Y-58319D01*
X1352658Y-58610D01*
X1351348Y-59485D01*
X1350475Y-61527D01*
X1350038Y-63277D01*
Y-65027D01*
X1350475Y-66777D01*
X1351567Y-68527D01*
X1352877Y-69693D01*
X1354405Y-69985D01*
X1355933Y-69402D01*
X1357462Y-67652D01*
G01X1368193Y-69985D02*
Y-58319D01*
G01Y-60652D02*
X1369285Y-59485D01*
X1370377Y-58610D01*
X1371905Y-58319D01*
X1372996Y-58610D01*
X1374307Y-59485D01*
G01X1401883Y-52485D02*
Y-69985D01*
X1410617D01*
G01X1419602Y-62694D02*
X1421130Y-60652D01*
X1422440Y-59485D01*
X1424187Y-58902D01*
X1425715Y-59485D01*
X1426807Y-60652D01*
X1427680Y-62402D01*
X1427898Y-64443D01*
X1427680Y-66194D01*
X1426807Y-67944D01*
X1425496Y-69402D01*
X1423968Y-69985D01*
X1422222Y-69402D01*
X1420693Y-67652D01*
X1419820Y-65027D01*
X1419602Y-62110D01*
X1420038Y-58319D01*
X1420693Y-56276D01*
X1421785Y-54235D01*
X1423313Y-52777D01*
X1424842Y-52485D01*
X1426370Y-53068D01*
X1427462Y-54527D01*
G01X1441250Y-70568D02*
X1440813Y-70277D01*
Y-69693D01*
X1441250Y-69402D01*
X1441687Y-69693D01*
Y-70277D01*
X1441250Y-70568D01*
G01X599509Y666709D02*
X601256Y665251D01*
X603221Y664376D01*
X604967D01*
X606714Y665251D01*
X608024Y666709D01*
X608679Y668751D01*
X608242Y670792D01*
X607151Y672543D01*
X605186Y673709D01*
X602566Y674293D01*
X601037Y675459D01*
X600382Y677501D01*
X600819Y679543D01*
X601911Y681001D01*
X603439Y681876D01*
X604967D01*
X606496Y681293D01*
X607806Y679834D01*
G01X625961Y664376D02*
X617227D01*
Y681876D01*
X625961D01*
G01X622467Y673418D02*
X617227D01*
G01X653974Y681876D02*
X659214D01*
G01X656594D02*
Y664376D01*
G01X653974D02*
X659214D01*
G01X668417D02*
Y681876D01*
X674094Y667293D01*
X679771Y681876D01*
Y664376D01*
G01X687227D02*
Y681876D01*
X692467D01*
X694214Y681001D01*
X695524Y678959D01*
X695961Y676626D01*
X695524Y674293D01*
X694432Y672543D01*
X692467Y671667D01*
X687227D01*
G01X713461Y664376D02*
X704727D01*
Y681876D01*
X713461D01*
G01X709967Y673418D02*
X704727D01*
G01X721791Y664376D02*
Y681876D01*
X726157D01*
X727904Y681001D01*
X729214Y679834D01*
X730306Y678085D01*
X731179Y676042D01*
X731397Y673126D01*
X731179Y670209D01*
X730306Y668167D01*
X729214Y666417D01*
X727904Y665251D01*
X726157Y664376D01*
X721791D01*
G01X738635D02*
X744094Y681876D01*
X749553Y664376D01*
G01X747587Y670501D02*
X740600D01*
G01X756572Y664376D02*
Y681876D01*
X766616Y664376D01*
Y681876D01*
G01X783897Y680417D02*
X782587Y681293D01*
X781059Y681876D01*
X779312D01*
X777347Y681001D01*
X775819Y679543D01*
X774727Y677792D01*
X773854Y674876D01*
X773635Y672251D01*
X774072Y669626D01*
X774727Y667876D01*
X776037Y666126D01*
X777566Y664959D01*
X779094Y664376D01*
X780622D01*
X782151Y664959D01*
X783461Y665834D01*
X784553Y667000D01*
G01X800961Y664376D02*
X792227D01*
Y681876D01*
X800961D01*
G01X797467Y673418D02*
X792227D01*
G01X831594Y681876D02*
Y664376D01*
G01X826572Y681876D02*
X836616D01*
G01X843635Y664376D02*
X849094Y681876D01*
X854553Y664376D01*
G01X852587Y670501D02*
X845600D01*
G01X868340Y673709D02*
X869214Y674584D01*
X869869Y676042D01*
X870306Y678085D01*
X869869Y679834D01*
X868996Y681001D01*
X867467Y681876D01*
X861572D01*
Y664376D01*
X868777D01*
X870306Y665542D01*
X871179Y667293D01*
X871616Y669334D01*
X871179Y671376D01*
X869869Y673126D01*
X868340Y673709D01*
X861572D01*
G01X879727Y681876D02*
Y664376D01*
X888461D01*
G01X905961D02*
X897227D01*
Y681876D01*
X905961D01*
G01X902467Y673418D02*
X897227D01*
G01X919094Y663793D02*
X918657Y664084D01*
Y664668D01*
X919094Y664959D01*
X919531Y664668D01*
Y664084D01*
X919094Y663793D01*
G01Y671667D02*
X918657Y671959D01*
Y672543D01*
X919094Y672834D01*
X919531Y672543D01*
Y671959D01*
X919094Y671667D01*
G01X949727Y681876D02*
Y664376D01*
X958461D01*
G01X967446Y671667D02*
X968974Y673709D01*
X970284Y674876D01*
X972031Y675459D01*
X973559Y674876D01*
X974651Y673709D01*
X975524Y671959D01*
X975742Y669918D01*
X975524Y668167D01*
X974651Y666417D01*
X973340Y664959D01*
X971812Y664376D01*
X970066Y664959D01*
X968537Y666709D01*
X967664Y669334D01*
X967446Y672251D01*
X967882Y676042D01*
X968537Y678085D01*
X969629Y680126D01*
X971157Y681584D01*
X972686Y681876D01*
X974214Y681293D01*
X975306Y679834D01*
G01X653991Y597700D02*
X655300Y596242D01*
X656829Y595368D01*
X658794Y595076D01*
X660759Y595659D01*
X662287Y596826D01*
X663379Y598867D01*
X663597Y601201D01*
X663161Y603534D01*
X662069Y604993D01*
X660540Y606159D01*
X659012Y606451D01*
X657484Y606159D01*
X655519Y604993D01*
X656174Y612576D01*
X662069D01*
G01X676294D02*
X674547Y611993D01*
X673237Y610534D01*
X672364Y608785D01*
X671709Y606451D01*
X671491Y603826D01*
X671709Y601201D01*
X672364Y598867D01*
X673237Y597117D01*
X674547Y595659D01*
X676294Y595076D01*
X678040Y595659D01*
X679351Y597117D01*
X680224Y598867D01*
X680879Y601201D01*
X681097Y603826D01*
X680879Y606451D01*
X680224Y608785D01*
X679351Y610534D01*
X678040Y611993D01*
X676294Y612576D01*
G01X693794Y594493D02*
X693357Y594784D01*
Y595368D01*
X693794Y595659D01*
X694231Y595368D01*
Y594784D01*
X693794Y594493D01*
G01X711294Y612576D02*
X709547Y611993D01*
X708237Y610534D01*
X707364Y608785D01*
X706709Y606451D01*
X706491Y603826D01*
X706709Y601201D01*
X707364Y598867D01*
X708237Y597117D01*
X709547Y595659D01*
X711294Y595076D01*
X713040Y595659D01*
X714351Y597117D01*
X715224Y598867D01*
X715879Y601201D01*
X716097Y603826D01*
X715879Y606451D01*
X715224Y608785D01*
X714351Y610534D01*
X713040Y611993D01*
X711294Y612576D01*
G01X621174Y647226D02*
X626414D01*
G01X623794D02*
Y629726D01*
G01X621174D02*
X626414D01*
G01X635617D02*
Y647226D01*
X641294Y632643D01*
X646971Y647226D01*
Y629726D01*
G01X654427D02*
Y647226D01*
X659667D01*
X661414Y646351D01*
X662724Y644309D01*
X663161Y641976D01*
X662724Y639643D01*
X661632Y637893D01*
X659667Y637017D01*
X654427D01*
G01X675202Y623893D02*
X673019Y626809D01*
X671927Y629726D01*
Y641392D01*
X673019Y644309D01*
X675202Y647226D01*
G01X693794Y629726D02*
X692047Y630018D01*
X690519Y631184D01*
X689209Y632934D01*
X688335Y634976D01*
X687899Y637309D01*
Y639643D01*
X688335Y641976D01*
X689209Y644018D01*
X690519Y645767D01*
X692047Y646934D01*
X693794Y647226D01*
X695540Y646934D01*
X697069Y645767D01*
X698379Y644018D01*
X699253Y641976D01*
X699689Y639643D01*
Y637309D01*
X699253Y634976D01*
X698379Y632934D01*
X697069Y631184D01*
X695540Y630018D01*
X693794Y629726D01*
G01X707582D02*
Y647226D01*
G01Y638768D02*
X708674Y640226D01*
X709766Y641101D01*
X711512Y641392D01*
X712822Y641101D01*
X714351Y639934D01*
X715006Y638184D01*
Y629726D01*
G01X722244D02*
Y641392D01*
G01Y638184D02*
X722899Y639643D01*
X723991Y640809D01*
X725519Y641392D01*
X727047Y640809D01*
X728139Y639643D01*
X728794Y638184D01*
Y629726D01*
G01Y638184D02*
X729449Y639643D01*
X730540Y640809D01*
X732069Y641392D01*
X733597Y640809D01*
X734689Y639643D01*
X735344Y637893D01*
Y629726D01*
G01X747386Y623893D02*
X749569Y626809D01*
X750661Y629726D01*
Y641392D01*
X749569Y644309D01*
X747386Y647226D01*
G01X792244D02*
X795300Y629726D01*
X798794Y647226D01*
X802287Y629726D01*
X805344Y647226D01*
G01X813674D02*
X818914D01*
G01X816294D02*
Y629726D01*
G01X813674D02*
X818914D01*
G01X828991D02*
Y647226D01*
X833357D01*
X835104Y646351D01*
X836414Y645184D01*
X837506Y643435D01*
X838379Y641392D01*
X838597Y638476D01*
X838379Y635559D01*
X837506Y633517D01*
X836414Y631767D01*
X835104Y630601D01*
X833357Y629726D01*
X828991D01*
G01X851294Y647226D02*
Y629726D01*
G01X846272Y647226D02*
X856316D01*
G01X864209Y629726D02*
Y647226D01*
G01X873379D02*
Y629726D01*
G01Y638476D02*
X864209D01*
G01X885202Y623893D02*
X883019Y626809D01*
X881927Y629726D01*
Y641392D01*
X883019Y644309D01*
X885202Y647226D01*
G01X897244Y629726D02*
Y641392D01*
G01Y638184D02*
X897899Y639643D01*
X898991Y640809D01*
X900519Y641392D01*
X902047Y640809D01*
X903139Y639643D01*
X903794Y638184D01*
Y629726D01*
G01Y638184D02*
X904449Y639643D01*
X905540Y640809D01*
X907069Y641392D01*
X908597Y640809D01*
X909689Y639643D01*
X910344Y637893D01*
Y629726D01*
G01X921294Y641392D02*
Y629726D01*
G01Y646059D02*
X920857Y646351D01*
Y646934D01*
X921294Y647226D01*
X921731Y646934D01*
Y646351D01*
X921294Y646059D01*
G01X938794Y629726D02*
Y647226D01*
G01X953019Y631767D02*
X954111Y630601D01*
X955639Y629726D01*
X956949D01*
X958259Y630309D01*
X959132Y631184D01*
X959569Y632350D01*
X959351Y634101D01*
X958477Y634976D01*
X954547Y636726D01*
X953674Y638768D01*
X954111Y640226D01*
X954984Y641101D01*
X956294Y641392D01*
X957604Y641101D01*
X958914Y640226D01*
G01X974886Y623893D02*
X977069Y626809D01*
X978161Y629726D01*
Y641392D01*
X977069Y644309D01*
X974886Y647226D01*
G01X868357Y595076D02*
X868794Y598867D01*
X869449Y602076D01*
X870322Y604993D01*
X871414Y608201D01*
X873161Y612576D01*
X864427D01*
G01X886294Y594493D02*
X885857Y594784D01*
Y595368D01*
X886294Y595659D01*
X886731Y595368D01*
Y594784D01*
X886294Y594493D01*
G01X903794Y612576D02*
X902047Y611993D01*
X900737Y610534D01*
X899864Y608785D01*
X899209Y606451D01*
X898991Y603826D01*
X899209Y601201D01*
X899864Y598867D01*
X900737Y597117D01*
X902047Y595659D01*
X903794Y595076D01*
X905540Y595659D01*
X906851Y597117D01*
X907724Y598867D01*
X908379Y601201D01*
X908597Y603826D01*
X908379Y606451D01*
X907724Y608785D01*
X906851Y610534D01*
X905540Y611993D01*
X903794Y612576D01*
G01X1026294Y647226D02*
Y629726D01*
G01X1021272Y647226D02*
X1031316D01*
G01X1043794Y629726D02*
Y637601D01*
X1039427Y647226D01*
G01X1048161D02*
X1043794Y637601D01*
G01X1056927Y629726D02*
Y647226D01*
X1062167D01*
X1063914Y646351D01*
X1065224Y644309D01*
X1065661Y641976D01*
X1065224Y639643D01*
X1064132Y637893D01*
X1062167Y637017D01*
X1056927D01*
G01X1083161Y629726D02*
X1074427D01*
Y647226D01*
X1083161D01*
G01X1079667Y638768D02*
X1074427D01*
G01X1039209Y597409D02*
X1040956Y595951D01*
X1042921Y595076D01*
X1044667D01*
X1046414Y595951D01*
X1047724Y597409D01*
X1048379Y599451D01*
X1047942Y601492D01*
X1046851Y603243D01*
X1044886Y604409D01*
X1042266Y604993D01*
X1040737Y606159D01*
X1040082Y608201D01*
X1040519Y610243D01*
X1041611Y611701D01*
X1043139Y612576D01*
X1044667D01*
X1046196Y611993D01*
X1047506Y610534D01*
G01X1065661Y595076D02*
X1056927D01*
Y612576D01*
X1065661D01*
G01X1062167Y604118D02*
X1056927D01*
G01X1126927Y629726D02*
Y647226D01*
X1132386D01*
X1134132Y646351D01*
X1135224Y645184D01*
X1135661Y642851D01*
X1135224Y640517D01*
X1133914Y639059D01*
X1132386Y638184D01*
X1126927D01*
G01X1132386D02*
X1135661Y629726D01*
G01X1145519Y637601D02*
X1152506D01*
X1151851Y639643D01*
X1150759Y640809D01*
X1149231Y641392D01*
X1147702Y641101D01*
X1146392Y640226D01*
X1145519Y638184D01*
X1145082Y636434D01*
Y634684D01*
X1145519Y632934D01*
X1146611Y631184D01*
X1147921Y630018D01*
X1149449Y629726D01*
X1150977Y630309D01*
X1152506Y632059D01*
G01X1164984Y629726D02*
Y644601D01*
X1165421Y646059D01*
X1166294Y646934D01*
X1167604Y647226D01*
X1168914Y646643D01*
X1169569Y645184D01*
G01X1166949Y640226D02*
X1162582D01*
G01X1183794Y629143D02*
X1183357Y629434D01*
Y630018D01*
X1183794Y630309D01*
X1184231Y630018D01*
Y629434D01*
X1183794Y629143D01*
G01X1214427Y629726D02*
Y647226D01*
X1219667D01*
X1221414Y646351D01*
X1222724Y644309D01*
X1223161Y641976D01*
X1222724Y639643D01*
X1221632Y637893D01*
X1219667Y637017D01*
X1214427D01*
G01X1236294Y629726D02*
Y647226D01*
G01X1257724Y629726D02*
Y641392D01*
G01Y639351D02*
X1256851Y640517D01*
X1255540Y641101D01*
X1254012Y641392D01*
X1252484Y640809D01*
X1251174Y639643D01*
X1250300Y637893D01*
X1249864Y635559D01*
X1250300Y633226D01*
X1251174Y631476D01*
X1252484Y630309D01*
X1254012Y629726D01*
X1255540Y630018D01*
X1256851Y630892D01*
X1257724Y632059D01*
G01X1267582Y629726D02*
Y641392D01*
G01Y638476D02*
X1268456Y639934D01*
X1269766Y641101D01*
X1271512Y641392D01*
X1273040Y641101D01*
X1274351Y639934D01*
X1275006Y637893D01*
Y629726D01*
G01X1285519Y637601D02*
X1292506D01*
X1291851Y639643D01*
X1290759Y640809D01*
X1289231Y641392D01*
X1287702Y641101D01*
X1286392Y640226D01*
X1285519Y638184D01*
X1285082Y636434D01*
Y634684D01*
X1285519Y632934D01*
X1286611Y631184D01*
X1287921Y630018D01*
X1289449Y629726D01*
X1290977Y630309D01*
X1292506Y632059D01*
G01X1196927Y612576D02*
Y595076D01*
X1205661D01*
G01X1213991Y597700D02*
X1215300Y596242D01*
X1216829Y595368D01*
X1218794Y595076D01*
X1220759Y595659D01*
X1222287Y596826D01*
X1223379Y598867D01*
X1223597Y601201D01*
X1223161Y603534D01*
X1222069Y604993D01*
X1220540Y606159D01*
X1219012Y606451D01*
X1217484Y606159D01*
X1215519Y604993D01*
X1216174Y612576D01*
X1222069D01*
G01X1406594Y606742D02*
Y595076D01*
G01Y611409D02*
X1406157Y611701D01*
Y612284D01*
X1406594Y612576D01*
X1407031Y612284D01*
Y611701D01*
X1406594Y611409D01*
G01X1420819Y597117D02*
X1421911Y595951D01*
X1423439Y595076D01*
X1424749D01*
X1426059Y595659D01*
X1426932Y596534D01*
X1427369Y597700D01*
X1427151Y599451D01*
X1426277Y600326D01*
X1422347Y602076D01*
X1421474Y604118D01*
X1421911Y605576D01*
X1422784Y606451D01*
X1424094Y606742D01*
X1425404Y606451D01*
X1426714Y605576D01*
G01X1454072Y595076D02*
Y612576D01*
X1464116Y595076D01*
Y612576D01*
G01X1476594Y595076D02*
X1474847Y595368D01*
X1473319Y596534D01*
X1472009Y598284D01*
X1471135Y600326D01*
X1470699Y602659D01*
Y604993D01*
X1471135Y607326D01*
X1472009Y609368D01*
X1473319Y611117D01*
X1474847Y612284D01*
X1476594Y612576D01*
X1478340Y612284D01*
X1479869Y611117D01*
X1481179Y609368D01*
X1482053Y607326D01*
X1482489Y604993D01*
Y602659D01*
X1482053Y600326D01*
X1481179Y598284D01*
X1479869Y596534D01*
X1478340Y595368D01*
X1476594Y595076D01*
G01X1494094Y612576D02*
Y595076D01*
G01X1489072Y612576D02*
X1499116D01*
G01X1525382Y606742D02*
Y598576D01*
X1526256Y596534D01*
X1527566Y595368D01*
X1529094Y595076D01*
X1530622Y595368D01*
X1531932Y596534D01*
X1532806Y598576D01*
G01Y595076D02*
Y606742D01*
G01X1543319Y597117D02*
X1544411Y595951D01*
X1545939Y595076D01*
X1547249D01*
X1548559Y595659D01*
X1549432Y596534D01*
X1549869Y597700D01*
X1549651Y599451D01*
X1548777Y600326D01*
X1544847Y602076D01*
X1543974Y604118D01*
X1544411Y605576D01*
X1545284Y606451D01*
X1546594Y606742D01*
X1547904Y606451D01*
X1549214Y605576D01*
G01X1560819Y602951D02*
X1567806D01*
X1567151Y604993D01*
X1566059Y606159D01*
X1564531Y606742D01*
X1563002Y606451D01*
X1561692Y605576D01*
X1560819Y603534D01*
X1560382Y601784D01*
Y600034D01*
X1560819Y598284D01*
X1561911Y596534D01*
X1563221Y595368D01*
X1564749Y595076D01*
X1566277Y595659D01*
X1567806Y597409D01*
G01X1585524Y612576D02*
Y595076D01*
G01Y597700D02*
X1584651Y596242D01*
X1583340Y595368D01*
X1581812Y595076D01*
X1580066Y595659D01*
X1578756Y597117D01*
X1577882Y598867D01*
X1577664Y600909D01*
X1577882Y602951D01*
X1578756Y604701D01*
X1580066Y606159D01*
X1581812Y606742D01*
X1583340Y606451D01*
X1584432Y605867D01*
X1585524Y604701D01*
G01X1616594Y606742D02*
Y595076D01*
G01Y611409D02*
X1616157Y611701D01*
Y612284D01*
X1616594Y612576D01*
X1617031Y612284D01*
Y611701D01*
X1616594Y611409D01*
G01X1630382Y595076D02*
Y606742D01*
G01Y603826D02*
X1631256Y605284D01*
X1632566Y606451D01*
X1634312Y606742D01*
X1635840Y606451D01*
X1637151Y605284D01*
X1637806Y603243D01*
Y595076D01*
G01X1669094Y612576D02*
Y595076D01*
G01X1666037Y606742D02*
X1672151D01*
G01X1682882Y595076D02*
Y612576D01*
G01Y604118D02*
X1683974Y605576D01*
X1685066Y606451D01*
X1686812Y606742D01*
X1688122Y606451D01*
X1689651Y605284D01*
X1690306Y603534D01*
Y595076D01*
G01X1704094Y606742D02*
Y595076D01*
G01Y611409D02*
X1703657Y611701D01*
Y612284D01*
X1704094Y612576D01*
X1704531Y612284D01*
Y611701D01*
X1704094Y611409D01*
G01X1718319Y597117D02*
X1719411Y595951D01*
X1720939Y595076D01*
X1722249D01*
X1723559Y595659D01*
X1724432Y596534D01*
X1724869Y597700D01*
X1724651Y599451D01*
X1723777Y600326D01*
X1719847Y602076D01*
X1718974Y604118D01*
X1719411Y605576D01*
X1720284Y606451D01*
X1721594Y606742D01*
X1722904Y606451D01*
X1724214Y605576D01*
G01X1756594Y595076D02*
Y612576D01*
G01X1778024Y595076D02*
Y606742D01*
G01Y604701D02*
X1777151Y605867D01*
X1775840Y606451D01*
X1774312Y606742D01*
X1772784Y606159D01*
X1771474Y604993D01*
X1770600Y603243D01*
X1770164Y600909D01*
X1770600Y598576D01*
X1771474Y596826D01*
X1772784Y595659D01*
X1774312Y595076D01*
X1775840Y595368D01*
X1777151Y596242D01*
X1778024Y597409D01*
G01X1787009Y589826D02*
X1788319Y589243D01*
X1790066Y589826D01*
X1791157Y590992D01*
X1792031Y592451D01*
X1793340Y597117D01*
X1796179Y606742D01*
G01X1789192D02*
X1793340Y597117D01*
G01X1805819Y602951D02*
X1812806D01*
X1812151Y604993D01*
X1811059Y606159D01*
X1809531Y606742D01*
X1808002Y606451D01*
X1806692Y605576D01*
X1805819Y603534D01*
X1805382Y601784D01*
Y600034D01*
X1805819Y598284D01*
X1806911Y596534D01*
X1808221Y595368D01*
X1809749Y595076D01*
X1811277Y595659D01*
X1812806Y597409D01*
G01X1823537Y595076D02*
Y606742D01*
G01Y604409D02*
X1824629Y605576D01*
X1825721Y606451D01*
X1827249Y606742D01*
X1828340Y606451D01*
X1829651Y605576D01*
G01X1406594Y572092D02*
Y560426D01*
G01Y576759D02*
X1406157Y577051D01*
Y577634D01*
X1406594Y577926D01*
X1407031Y577634D01*
Y577051D01*
X1406594Y576759D01*
G01X1420382Y560426D02*
Y572092D01*
G01Y569176D02*
X1421256Y570634D01*
X1422566Y571801D01*
X1424312Y572092D01*
X1425840Y571801D01*
X1427151Y570634D01*
X1427806Y568593D01*
Y560426D01*
G01X1438319Y562467D02*
X1439411Y561301D01*
X1440939Y560426D01*
X1442249D01*
X1443559Y561009D01*
X1444432Y561884D01*
X1444869Y563050D01*
X1444651Y564801D01*
X1443777Y565676D01*
X1439847Y567426D01*
X1438974Y569468D01*
X1439411Y570926D01*
X1440284Y571801D01*
X1441594Y572092D01*
X1442904Y571801D01*
X1444214Y570926D01*
G01X1459094Y572092D02*
Y560426D01*
G01Y576759D02*
X1458657Y577051D01*
Y577634D01*
X1459094Y577926D01*
X1459531Y577634D01*
Y577051D01*
X1459094Y576759D01*
G01X1480524Y577926D02*
Y560426D01*
G01Y563050D02*
X1479651Y561592D01*
X1478340Y560718D01*
X1476812Y560426D01*
X1475066Y561009D01*
X1473756Y562467D01*
X1472882Y564217D01*
X1472664Y566259D01*
X1472882Y568301D01*
X1473756Y570051D01*
X1475066Y571509D01*
X1476812Y572092D01*
X1478340Y571801D01*
X1479432Y571217D01*
X1480524Y570051D01*
G01X1490819Y568301D02*
X1497806D01*
X1497151Y570343D01*
X1496059Y571509D01*
X1494531Y572092D01*
X1493002Y571801D01*
X1491692Y570926D01*
X1490819Y568884D01*
X1490382Y567134D01*
Y565384D01*
X1490819Y563634D01*
X1491911Y561884D01*
X1493221Y560718D01*
X1494749Y560426D01*
X1496277Y561009D01*
X1497806Y562759D01*
G01X1525164Y560426D02*
Y577926D01*
G01Y569176D02*
X1526256Y570926D01*
X1527566Y571801D01*
X1528876Y572092D01*
X1530840Y571509D01*
X1532151Y570343D01*
X1533024Y568301D01*
Y565968D01*
X1532587Y563634D01*
X1531714Y561884D01*
X1530186Y560718D01*
X1528876Y560426D01*
X1527566Y560718D01*
X1526256Y561592D01*
X1525164Y563050D01*
G01X1546594Y560426D02*
X1545284Y560718D01*
X1543974Y561884D01*
X1543100Y563926D01*
X1542664Y566259D01*
X1543100Y568593D01*
X1543974Y570634D01*
X1545284Y571801D01*
X1546594Y572092D01*
X1547904Y571801D01*
X1549214Y570634D01*
X1550087Y568593D01*
X1550306Y566259D01*
X1550087Y563926D01*
X1549214Y561884D01*
X1547904Y560718D01*
X1546594Y560426D01*
G01X1568024D02*
Y572092D01*
G01Y570051D02*
X1567151Y571217D01*
X1565840Y571801D01*
X1564312Y572092D01*
X1562784Y571509D01*
X1561474Y570343D01*
X1560600Y568593D01*
X1560164Y566259D01*
X1560600Y563926D01*
X1561474Y562176D01*
X1562784Y561009D01*
X1564312Y560426D01*
X1565840Y560718D01*
X1567151Y561592D01*
X1568024Y562759D01*
G01X1578537Y560426D02*
Y572092D01*
G01Y569759D02*
X1579629Y570926D01*
X1580721Y571801D01*
X1582249Y572092D01*
X1583340Y571801D01*
X1584651Y570926D01*
G01X1603024Y577926D02*
Y560426D01*
G01Y563050D02*
X1602151Y561592D01*
X1600840Y560718D01*
X1599312Y560426D01*
X1597566Y561009D01*
X1596256Y562467D01*
X1595382Y564217D01*
X1595164Y566259D01*
X1595382Y568301D01*
X1596256Y570051D01*
X1597566Y571509D01*
X1599312Y572092D01*
X1600840Y571801D01*
X1601932Y571217D01*
X1603024Y570051D01*
G01X1634094Y560426D02*
X1632784Y560718D01*
X1631474Y561884D01*
X1630600Y563926D01*
X1630164Y566259D01*
X1630600Y568593D01*
X1631474Y570634D01*
X1632784Y571801D01*
X1634094Y572092D01*
X1635404Y571801D01*
X1636714Y570634D01*
X1637587Y568593D01*
X1637806Y566259D01*
X1637587Y563926D01*
X1636714Y561884D01*
X1635404Y560718D01*
X1634094Y560426D01*
G01X1647882Y572092D02*
Y563926D01*
X1648756Y561884D01*
X1650066Y560718D01*
X1651594Y560426D01*
X1653122Y560718D01*
X1654432Y561884D01*
X1655306Y563926D01*
G01Y560426D02*
Y572092D01*
G01X1669094Y577926D02*
Y560426D01*
G01X1666037Y572092D02*
X1672151D01*
G01X1686594Y560426D02*
Y577926D01*
G01X1704094Y572092D02*
Y560426D01*
G01Y576759D02*
X1703657Y577051D01*
Y577634D01*
X1704094Y577926D01*
X1704531Y577634D01*
Y577051D01*
X1704094Y576759D01*
G01X1717882Y560426D02*
Y572092D01*
G01Y569176D02*
X1718756Y570634D01*
X1720066Y571801D01*
X1721812Y572092D01*
X1723340Y571801D01*
X1724651Y570634D01*
X1725306Y568593D01*
Y560426D01*
G01X1735819Y568301D02*
X1742806D01*
X1742151Y570343D01*
X1741059Y571509D01*
X1739531Y572092D01*
X1738002Y571801D01*
X1736692Y570926D01*
X1735819Y568884D01*
X1735382Y567134D01*
Y565384D01*
X1735819Y563634D01*
X1736911Y561884D01*
X1738221Y560718D01*
X1739749Y560426D01*
X1741277Y561009D01*
X1742806Y562759D01*
G01X1756594Y559843D02*
X1756157Y560134D01*
Y560718D01*
X1756594Y561009D01*
X1757031Y560718D01*
Y560134D01*
X1756594Y559843D01*
G01X1331791Y629143D02*
X1341397Y641976D01*
G01X1336594Y644309D02*
Y626809D01*
G01X1341397Y629143D02*
X1331791Y641976D01*
G01X1330044Y635559D02*
X1343144D01*
G01X1368756D02*
X1374432D01*
G01X1401791Y629726D02*
Y647226D01*
X1406157D01*
X1407904Y646351D01*
X1409214Y645184D01*
X1410306Y643435D01*
X1411179Y641392D01*
X1411397Y638476D01*
X1411179Y635559D01*
X1410306Y633517D01*
X1409214Y631767D01*
X1407904Y630601D01*
X1406157Y629726D01*
X1401791D01*
G01X1420819Y637601D02*
X1427806D01*
X1427151Y639643D01*
X1426059Y640809D01*
X1424531Y641392D01*
X1423002Y641101D01*
X1421692Y640226D01*
X1420819Y638184D01*
X1420382Y636434D01*
Y634684D01*
X1420819Y632934D01*
X1421911Y631184D01*
X1423221Y630018D01*
X1424749Y629726D01*
X1426277Y630309D01*
X1427806Y632059D01*
G01X1437882Y629726D02*
Y641392D01*
G01Y638476D02*
X1438756Y639934D01*
X1440066Y641101D01*
X1441812Y641392D01*
X1443340Y641101D01*
X1444651Y639934D01*
X1445306Y637893D01*
Y629726D01*
G01X1459094D02*
X1457784Y630018D01*
X1456474Y631184D01*
X1455600Y633226D01*
X1455164Y635559D01*
X1455600Y637893D01*
X1456474Y639934D01*
X1457784Y641101D01*
X1459094Y641392D01*
X1460404Y641101D01*
X1461714Y639934D01*
X1462587Y637893D01*
X1462806Y635559D01*
X1462587Y633226D01*
X1461714Y631184D01*
X1460404Y630018D01*
X1459094Y629726D01*
G01X1476594Y647226D02*
Y629726D01*
G01X1473537Y641392D02*
X1479651D01*
G01X1490819Y637601D02*
X1497806D01*
X1497151Y639643D01*
X1496059Y640809D01*
X1494531Y641392D01*
X1493002Y641101D01*
X1491692Y640226D01*
X1490819Y638184D01*
X1490382Y636434D01*
Y634684D01*
X1490819Y632934D01*
X1491911Y631184D01*
X1493221Y630018D01*
X1494749Y629726D01*
X1496277Y630309D01*
X1497806Y632059D01*
G01X1508319Y631767D02*
X1509411Y630601D01*
X1510939Y629726D01*
X1512249D01*
X1513559Y630309D01*
X1514432Y631184D01*
X1514869Y632350D01*
X1514651Y634101D01*
X1513777Y634976D01*
X1509847Y636726D01*
X1508974Y638768D01*
X1509411Y640226D01*
X1510284Y641101D01*
X1511594Y641392D01*
X1512904Y641101D01*
X1514214Y640226D01*
G01X1546594Y647226D02*
Y629726D01*
G01X1543537Y641392D02*
X1549651D01*
G01X1560382Y629726D02*
Y647226D01*
G01Y638768D02*
X1561474Y640226D01*
X1562566Y641101D01*
X1564312Y641392D01*
X1565622Y641101D01*
X1567151Y639934D01*
X1567806Y638184D01*
Y629726D01*
G01X1585524D02*
Y641392D01*
G01Y639351D02*
X1584651Y640517D01*
X1583340Y641101D01*
X1581812Y641392D01*
X1580284Y640809D01*
X1578974Y639643D01*
X1578100Y637893D01*
X1577664Y635559D01*
X1578100Y633226D01*
X1578974Y631476D01*
X1580284Y630309D01*
X1581812Y629726D01*
X1583340Y630018D01*
X1584651Y630892D01*
X1585524Y632059D01*
G01X1599094Y647226D02*
Y629726D01*
G01X1596037Y641392D02*
X1602151D01*
G01X1627544Y647226D02*
X1630600Y629726D01*
X1634094Y647226D01*
X1637587Y629726D01*
X1640644Y647226D01*
G01X1648974D02*
X1654214D01*
G01X1651594D02*
Y629726D01*
G01X1648974D02*
X1654214D01*
G01X1664291D02*
Y647226D01*
X1668657D01*
X1670404Y646351D01*
X1671714Y645184D01*
X1672806Y643435D01*
X1673679Y641392D01*
X1673897Y638476D01*
X1673679Y635559D01*
X1672806Y633517D01*
X1671714Y631767D01*
X1670404Y630601D01*
X1668657Y629726D01*
X1664291D01*
G01X1686594Y647226D02*
Y629726D01*
G01X1681572Y647226D02*
X1691616D01*
G01X1699509Y629726D02*
Y647226D01*
G01X1708679D02*
Y629726D01*
G01Y638476D02*
X1699509D01*
G01X0Y-11811D02*
G03X7874Y-19685I7874J0D01*
G01X37008Y0D02*
G03Y-7874I0J-3937D01*
G01X11811D02*
G03Y0I0J3937D01*
G01X0Y-7874D02*
Y-11811D01*
G01X7874Y-19685D02*
X181690D01*
G01X0Y-7874D02*
X11811D01*
G01X25985Y19685D02*
G03X9449I-8268J0D01*
G01D02*
G03X25985I8268J0D01*
G01D02*
G03X9449I-8268J0D01*
G01D02*
G03X25985I8268J0D01*
G01D02*
G03X9449I-8268J0D01*
G01D02*
G03X25985I8268J0D01*
G01D02*
G03X9449I-8268J0D01*
G01D02*
G03X25985I8268J0D01*
G01X9449D02*
G03X25985I8268J0D01*
G01D02*
G03X9449I-8268J0D01*
G01D02*
G03X25985I8268J0D01*
G01D02*
G03X9449I-8268J0D01*
G01X3937Y0D02*
X173229D01*
G01X0Y3937D02*
G03X3937Y0I3937J0D01*
G01X0Y57874D02*
Y3937D01*
G01X37008Y69685D02*
G03Y61811I0J-3937D01*
G01X11811D02*
G03Y69685I0J3937D01*
G01X25985Y89370D02*
G03X9449I-8268J0D01*
G01D02*
G03X25985I8268J0D01*
G01D02*
G03X9449I-8268J0D01*
G01D02*
G03X25985I8268J0D01*
G01D02*
G03X9449I-8268J0D01*
G01D02*
G03X25985I8268J0D01*
G01D02*
G03X9449I-8268J0D01*
G01D02*
G03X25985I8268J0D01*
G01X9449D02*
G03X25985I8268J0D01*
G01D02*
G03X9449I-8268J0D01*
G01D02*
G03X25985I8268J0D01*
G01D02*
G03X9449I-8268J0D01*
G01X3937Y69685D02*
X173229D01*
G01X0Y73622D02*
G03X3937Y69685I3937J0D01*
G01X0Y127559D02*
Y73622D01*
G01X3937Y61811D02*
G03X0Y57874I0J-3937D01*
G01X173229Y61811D02*
X3937D01*
G01X37008Y139370D02*
G03Y131496I0J-3937D01*
G01X11811D02*
G03Y139370I0J3937D01*
G01X25985Y159055D02*
G03X9449I-8268J0D01*
G01D02*
G03X25985I8268J0D01*
G01D02*
G03X9449I-8268J0D01*
G01D02*
G03X25985I8268J0D01*
G01D02*
G03X9449I-8268J0D01*
G01D02*
G03X25985I8268J0D01*
G01D02*
G03X9449I-8268J0D01*
G01D02*
G03X25985I8268J0D01*
G01X9449D02*
G03X25985I8268J0D01*
G01D02*
G03X9449I-8268J0D01*
G01D02*
G03X25985I8268J0D01*
G01D02*
G03X9449I-8268J0D01*
G01X3937Y139370D02*
X173229D01*
G01X0Y143307D02*
G03X3937Y139370I3937J0D01*
G01X0Y197244D02*
Y143307D01*
G01X3937Y131496D02*
G03X0Y127559I0J-3937D01*
G01X173229Y131496D02*
X3937D01*
G01X37008Y278740D02*
G03Y270866I0J-3937D01*
G01X11811D02*
G03Y278740I0J3937D01*
G01X37008Y209055D02*
G03Y201181I0J-3937D01*
G01X11811D02*
G03Y209055I0J3937D01*
G01X3937Y278740D02*
X173229D01*
G01X0Y282677D02*
G03X3937Y278740I3937J0D01*
G01X25985Y228740D02*
G03X9449I-8268J0D01*
G01D02*
G03X25985I8268J0D01*
G01D02*
G03X9449I-8268J0D01*
G01D02*
G03X25985I8268J0D01*
G01D02*
G03X9449I-8268J0D01*
G01D02*
G03X25985I8268J0D01*
G01D02*
G03X9449I-8268J0D01*
G01D02*
G03X25985I8268J0D01*
G01X9449D02*
G03X25985I8268J0D01*
G01D02*
G03X9449I-8268J0D01*
G01D02*
G03X25985I8268J0D01*
G01D02*
G03X9449I-8268J0D01*
G01X3937Y209055D02*
X173229D01*
G01X0Y212992D02*
G03X3937Y209055I3937J0D01*
G01X0Y266929D02*
Y212992D01*
G01X3937Y270866D02*
G03X0Y266929I0J-3937D01*
G01X173229Y270866D02*
X3937D01*
G01Y201181D02*
G03X0Y197244I0J-3937D01*
G01X173229Y201181D02*
X3937D01*
G01X37008Y348425D02*
G03Y340551I0J-3937D01*
G01X11811D02*
G03Y348425I0J3937D01*
G01X9449Y368110D02*
G03X25985I8268J0D01*
G01X9449D02*
G03X25985I8268J0D01*
G01X9449D02*
G03X25985I8268J0D01*
G01X9449D02*
G03X25985I8268J0D01*
G01X9449D02*
G03X25985I8268J0D01*
G01X9449D02*
G03X25985I8268J0D01*
G01X3937Y348425D02*
X173229D01*
G01X0Y352362D02*
G03X3937Y348425I3937J0D01*
G01X0Y406299D02*
Y352362D01*
G01X25985Y298425D02*
G03X9449I-8268J0D01*
G01D02*
G03X25985I8268J0D01*
G01D02*
G03X9449I-8268J0D01*
G01D02*
G03X25985I8268J0D01*
G01D02*
G03X9449I-8268J0D01*
G01D02*
G03X25985I8268J0D01*
G01D02*
G03X9449I-8268J0D01*
G01D02*
G03X25985I8268J0D01*
G01X9449D02*
G03X25985I8268J0D01*
G01D02*
G03X9449I-8268J0D01*
G01D02*
G03X25985I8268J0D01*
G01D02*
G03X9449I-8268J0D01*
G01X0Y336614D02*
Y282677D01*
G01X3937Y340551D02*
G03X0Y336614I0J-3937D01*
G01X173229Y340551D02*
X3937D01*
G01X37008Y418110D02*
G03Y410236I0J-3937D01*
G01X11811D02*
G03Y418110I0J3937D01*
G01X25985Y437795D02*
G03X9449I-8268J0D01*
G01D02*
G03X25985I8268J0D01*
G01D02*
G03X9449I-8268J0D01*
G01D02*
G03X25985I8268J0D01*
G01D02*
G03X9449I-8268J0D01*
G01D02*
G03X25985I8268J0D01*
G01D02*
G03X9449I-8268J0D01*
G01D02*
G03X25985I8268J0D01*
G01X9449D02*
G03X25985I8268J0D01*
G01D02*
G03X9449I-8268J0D01*
G01D02*
G03X25985I8268J0D01*
G01D02*
G03X9449I-8268J0D01*
G01X3937Y418110D02*
X173229D01*
G01X0Y422047D02*
G03X3937Y418110I3937J0D01*
G01X0Y475984D02*
Y422047D01*
G01X25985Y368110D02*
G03X9449I-8268J0D01*
G01X25985D02*
G03X9449I-8268J0D01*
G01X25985D02*
G03X9449I-8268J0D01*
G01X25985D02*
G03X9449I-8268J0D01*
G01X25985D02*
G03X9449I-8268J0D01*
G01X25985D02*
G03X9449I-8268J0D01*
G01X3937Y410236D02*
G03X0Y406299I0J-3937D01*
G01X173229Y410236D02*
X3937D01*
G01X37008Y487795D02*
G03Y479921I0J-3937D01*
G01X11811D02*
G03Y487795I0J3937D01*
G01X25985Y507480D02*
G03X9449I-8268J0D01*
G01D02*
G03X25985I8268J0D01*
G01D02*
G03X9449I-8268J0D01*
G01D02*
G03X25985I8268J0D01*
G01D02*
G03X9449I-8268J0D01*
G01D02*
G03X25985I8268J0D01*
G01D02*
G03X9449I-8268J0D01*
G01D02*
G03X25985I8268J0D01*
G01X9449D02*
G03X25985I8268J0D01*
G01D02*
G03X9449I-8268J0D01*
G01D02*
G03X25985I8268J0D01*
G01D02*
G03X9449I-8268J0D01*
G01X3937Y487795D02*
X173229D01*
G01X0Y491732D02*
G03X3937Y487795I3937J0D01*
G01X0Y545669D02*
Y491732D01*
G01X3937Y479921D02*
G03X0Y475984I0J-3937D01*
G01X173229Y479921D02*
X3937D01*
G01X37008Y557480D02*
G03Y549606I0J-3937D01*
G01X11811D02*
G03Y557480I0J3937D01*
G01X25985Y577165D02*
G03X9449I-8268J0D01*
G01D02*
G03X25985I8268J0D01*
G01D02*
G03X9449I-8268J0D01*
G01D02*
G03X25985I8268J0D01*
G01D02*
G03X9449I-8268J0D01*
G01D02*
G03X25985I8268J0D01*
G01D02*
G03X9449I-8268J0D01*
G01D02*
G03X25985I8268J0D01*
G01X9449D02*
G03X25985I8268J0D01*
G01D02*
G03X9449I-8268J0D01*
G01D02*
G03X25985I8268J0D01*
G01D02*
G03X9449I-8268J0D01*
G01X3937Y557480D02*
X173229D01*
G01X0Y561417D02*
G03X3937Y557480I3937J0D01*
G01X0Y615354D02*
Y561417D01*
G01X3937Y549606D02*
G03X0Y545669I0J-3937D01*
G01X173229Y549606D02*
X3937D01*
G01X37008Y627165D02*
G03Y619291I0J-3937D01*
G01X11811D02*
G03Y627165I0J3937D01*
G01X25985Y646850D02*
G03X9449I-8268J0D01*
G01D02*
G03X25985I8268J0D01*
G01D02*
G03X9449I-8268J0D01*
G01D02*
G03X25985I8268J0D01*
G01D02*
G03X9449I-8268J0D01*
G01D02*
G03X25985I8268J0D01*
G01D02*
G03X9449I-8268J0D01*
G01D02*
G03X25985I8268J0D01*
G01X9449D02*
G03X25985I8268J0D01*
G01D02*
G03X9449I-8268J0D01*
G01D02*
G03X25985I8268J0D01*
G01D02*
G03X9449I-8268J0D01*
G01X3937Y627165D02*
X173229D01*
G01X0Y631102D02*
G03X3937Y627165I3937J0D01*
G01X0Y685039D02*
Y631102D01*
G01X3937Y688976D02*
G03X0Y685039I0J-3937D01*
G01X173229Y688976D02*
X3937D01*
G01Y619291D02*
G03X0Y615354I0J-3937D01*
G01X173229Y619291D02*
X3937D01*
G01X37008Y-7874D02*
X140158D01*
G01X196851D02*
G03Y0I0J3937D01*
G01X189564Y-19685D02*
G03X181690I-3937J0D01*
G01X165355Y0D02*
G03Y-7874I0J-3937D01*
G01X140158D02*
G03Y0I0J3937D01*
G01X185040Y18307D02*
G03X177166I-3937J0D01*
G01X189564Y-19685D02*
X539370D01*
G01X165355Y-7874D02*
X196851D01*
G01X211024Y19685D02*
G03X194489I-8267J0D01*
G01D02*
G03X211024I8267J0D01*
G01D02*
G03X194489I-8267J0D01*
G01D02*
G03X211024I8267J0D01*
G01D02*
G03X194489I-8267J0D01*
G01D02*
G03X211024I8267J0D01*
G01D02*
G03X194489I-8267J0D01*
G01D02*
G03X211024I8267J0D01*
G01X194489D02*
G03X211024I8267J0D01*
G01D02*
G03X194489I-8267J0D01*
G01D02*
G03X211024I8267J0D01*
G01D02*
G03X194489I-8267J0D01*
G01X188977Y0D02*
X358268D01*
G01X185040Y3937D02*
G03X188977Y0I3937J0D01*
G01X185040Y57874D02*
Y3937D01*
G01X167717Y19685D02*
G03X151181I-8268J0D01*
G01D02*
G03X167717I8268J0D01*
G01D02*
G03X151181I-8268J0D01*
G01D02*
G03X167717I8268J0D01*
G01D02*
G03X151181I-8268J0D01*
G01D02*
G03X167717I8268J0D01*
G01D02*
G03X151181I-8268J0D01*
G01D02*
G03X167717I8268J0D01*
G01X151181D02*
G03X167717I8268J0D01*
G01D02*
G03X151181I-8268J0D01*
G01D02*
G03X167717I8268J0D01*
G01D02*
G03X151181I-8268J0D01*
G01X177166Y3937D02*
Y57874D01*
G01X173229Y0D02*
G03X177166Y3937I0J3937D01*
G01X185040Y87992D02*
G03X177166I-3937J0D01*
G01Y113189D02*
G03X185040I3937J0D01*
G01X196851Y61811D02*
G03Y69685I0J3937D01*
G01X165355D02*
G03Y61811I0J-3937D01*
G01X140158D02*
G03Y69685I0J3937D01*
G01X177166Y43504D02*
G03X185040I3937J0D01*
G01X167717Y89370D02*
G03X151181I-8268J0D01*
G01D02*
G03X167717I8268J0D01*
G01D02*
G03X151181I-8268J0D01*
G01D02*
G03X167717I8268J0D01*
G01D02*
G03X151181I-8268J0D01*
G01D02*
G03X167717I8268J0D01*
G01D02*
G03X151181I-8268J0D01*
G01D02*
G03X167717I8268J0D01*
G01X151181D02*
G03X167717I8268J0D01*
G01D02*
G03X151181I-8268J0D01*
G01D02*
G03X167717I8268J0D01*
G01D02*
G03X151181I-8268J0D01*
G01X177166Y73622D02*
Y127559D01*
G01X173229Y69685D02*
G03X177166Y73622I0J3937D01*
G01X211024Y89370D02*
G03X194489I-8267J0D01*
G01D02*
G03X211024I8267J0D01*
G01D02*
G03X194489I-8267J0D01*
G01D02*
G03X211024I8267J0D01*
G01D02*
G03X194489I-8267J0D01*
G01D02*
G03X211024I8267J0D01*
G01D02*
G03X194489I-8267J0D01*
G01D02*
G03X211024I8267J0D01*
G01X194489D02*
G03X211024I8267J0D01*
G01D02*
G03X194489I-8267J0D01*
G01D02*
G03X211024I8267J0D01*
G01D02*
G03X194489I-8267J0D01*
G01X188977Y69685D02*
X358268D01*
G01X185040Y73622D02*
G03X188977Y69685I3937J0D01*
G01X185040Y127559D02*
Y73622D01*
G01X188977Y61811D02*
G03X185040Y57874I0J-3937D01*
G01X358268Y61811D02*
X188977D01*
G01X177166Y57874D02*
G03X173229Y61811I-3937J0D01*
G01X185040Y157677D02*
G03X177166I-3937J0D01*
G01Y182874D02*
G03X185040I3937J0D01*
G01X196851Y131496D02*
G03Y139370I0J3937D01*
G01X165355D02*
G03Y131496I0J-3937D01*
G01X140158D02*
G03Y139370I0J3937D01*
G01X167717Y159055D02*
G03X151181I-8268J0D01*
G01D02*
G03X167717I8268J0D01*
G01D02*
G03X151181I-8268J0D01*
G01D02*
G03X167717I8268J0D01*
G01D02*
G03X151181I-8268J0D01*
G01D02*
G03X167717I8268J0D01*
G01D02*
G03X151181I-8268J0D01*
G01D02*
G03X167717I8268J0D01*
G01X151181D02*
G03X167717I8268J0D01*
G01D02*
G03X151181I-8268J0D01*
G01D02*
G03X167717I8268J0D01*
G01D02*
G03X151181I-8268J0D01*
G01X177166Y143307D02*
Y197244D01*
G01X173229Y139370D02*
G03X177166Y143307I0J3937D01*
G01Y127559D02*
G03X173229Y131496I-3937J0D01*
G01X211024Y159055D02*
G03X194489I-8267J0D01*
G01D02*
G03X211024I8267J0D01*
G01D02*
G03X194489I-8267J0D01*
G01D02*
G03X211024I8267J0D01*
G01D02*
G03X194489I-8267J0D01*
G01D02*
G03X211024I8267J0D01*
G01D02*
G03X194489I-8267J0D01*
G01D02*
G03X211024I8267J0D01*
G01X194489D02*
G03X211024I8267J0D01*
G01D02*
G03X194489I-8267J0D01*
G01D02*
G03X211024I8267J0D01*
G01D02*
G03X194489I-8267J0D01*
G01X188977Y139370D02*
X358268D01*
G01X185040Y143307D02*
G03X188977Y139370I3937J0D01*
G01X185040Y197244D02*
Y143307D01*
G01X188977Y131496D02*
G03X185040Y127559I0J-3937D01*
G01X358268Y131496D02*
X188977D01*
G01X185040Y227362D02*
G03X177166I-3937J0D01*
G01Y252559D02*
G03X185040I3937J0D01*
G01X196851Y270866D02*
G03Y278740I0J3937D01*
G01X165355D02*
G03Y270866I0J-3937D01*
G01X140158D02*
G03Y278740I0J3937D01*
G01X196851Y201181D02*
G03Y209055I0J3937D01*
G01X165355D02*
G03Y201181I0J-3937D01*
G01X140158D02*
G03Y209055I0J3937D01*
G01X173229Y278740D02*
G03X177166Y282677I0J3937D01*
G01X188977Y278740D02*
X358268D01*
G01X185040Y282677D02*
G03X188977Y278740I3937J0D01*
G01X167717Y228740D02*
G03X151181I-8268J0D01*
G01D02*
G03X167717I8268J0D01*
G01D02*
G03X151181I-8268J0D01*
G01D02*
G03X167717I8268J0D01*
G01D02*
G03X151181I-8268J0D01*
G01D02*
G03X167717I8268J0D01*
G01D02*
G03X151181I-8268J0D01*
G01D02*
G03X167717I8268J0D01*
G01X151181D02*
G03X167717I8268J0D01*
G01D02*
G03X151181I-8268J0D01*
G01D02*
G03X167717I8268J0D01*
G01D02*
G03X151181I-8268J0D01*
G01X177166Y212992D02*
Y266929D01*
G01X173229Y209055D02*
G03X177166Y212992I0J3937D01*
G01Y266929D02*
G03X173229Y270866I-3937J0D01*
G01X211024Y228740D02*
G03X194489I-8267J0D01*
G01D02*
G03X211024I8267J0D01*
G01D02*
G03X194489I-8267J0D01*
G01D02*
G03X211024I8267J0D01*
G01D02*
G03X194489I-8267J0D01*
G01D02*
G03X211024I8267J0D01*
G01D02*
G03X194489I-8267J0D01*
G01D02*
G03X211024I8267J0D01*
G01X194489D02*
G03X211024I8267J0D01*
G01D02*
G03X194489I-8267J0D01*
G01D02*
G03X211024I8267J0D01*
G01D02*
G03X194489I-8267J0D01*
G01X188977Y209055D02*
X358268D01*
G01X185040Y212992D02*
G03X188977Y209055I3937J0D01*
G01X185040Y266929D02*
Y212992D01*
G01X188977Y270866D02*
G03X185040Y266929I0J-3937D01*
G01X358268Y270866D02*
X188977D01*
G01X177166Y197244D02*
G03X173229Y201181I-3937J0D01*
G01X188977D02*
G03X185040Y197244I0J-3937D01*
G01X358268Y201181D02*
X188977D01*
G01X185040Y297047D02*
G03X177166I-3937J0D01*
G01Y322244D02*
G03X185040I3937J0D01*
G01X196851Y340551D02*
G03Y348425I0J3937D01*
G01X165355D02*
G03Y340551I0J-3937D01*
G01X140158D02*
G03Y348425I0J3937D01*
G01X151181Y368110D02*
G03X167717I8268J0D01*
G01X151181D02*
G03X167717I8268J0D01*
G01X151181D02*
G03X167717I8268J0D01*
G01X151181D02*
G03X167717I8268J0D01*
G01X151181D02*
G03X167717I8268J0D01*
G01X151181D02*
G03X167717I8268J0D01*
G01X177166Y352362D02*
Y406299D01*
G01X173229Y348425D02*
G03X177166Y352362I0J3937D01*
G01X194489Y368110D02*
G03X211024I8267J0D01*
G01X194489D02*
G03X211024I8267J0D01*
G01X194489D02*
G03X211024I8267J0D01*
G01X194489D02*
G03X211024I8267J0D01*
G01X194489D02*
G03X211024I8267J0D01*
G01X194489D02*
G03X211024I8267J0D01*
G01X188977Y348425D02*
X358268D01*
G01X185040Y352362D02*
G03X188977Y348425I3937J0D01*
G01X185040Y406299D02*
Y352362D01*
G01X167717Y298425D02*
G03X151181I-8268J0D01*
G01D02*
G03X167717I8268J0D01*
G01D02*
G03X151181I-8268J0D01*
G01D02*
G03X167717I8268J0D01*
G01D02*
G03X151181I-8268J0D01*
G01D02*
G03X167717I8268J0D01*
G01D02*
G03X151181I-8268J0D01*
G01D02*
G03X167717I8268J0D01*
G01X151181D02*
G03X167717I8268J0D01*
G01D02*
G03X151181I-8268J0D01*
G01D02*
G03X167717I8268J0D01*
G01D02*
G03X151181I-8268J0D01*
G01X177166Y282677D02*
Y336614D01*
G01D02*
G03X173229Y340551I-3937J0D01*
G01X211024Y298425D02*
G03X194489I-8267J0D01*
G01D02*
G03X211024I8267J0D01*
G01D02*
G03X194489I-8267J0D01*
G01D02*
G03X211024I8267J0D01*
G01D02*
G03X194489I-8267J0D01*
G01D02*
G03X211024I8267J0D01*
G01D02*
G03X194489I-8267J0D01*
G01D02*
G03X211024I8267J0D01*
G01X194489D02*
G03X211024I8267J0D01*
G01D02*
G03X194489I-8267J0D01*
G01D02*
G03X211024I8267J0D01*
G01D02*
G03X194489I-8267J0D01*
G01X185040Y336614D02*
Y282677D01*
G01X188977Y340551D02*
G03X185040Y336614I0J-3937D01*
G01X358268Y340551D02*
X188977D01*
G01X185040Y436417D02*
G03X177166I-3937J0D01*
G01X185040Y366732D02*
G03X177166I-3937J0D01*
G01Y391929D02*
G03X185040I3937J0D01*
G01X196851Y410236D02*
G03Y418110I0J3937D01*
G01X165355D02*
G03Y410236I0J-3937D01*
G01X140158D02*
G03Y418110I0J3937D01*
G01X167717Y437795D02*
G03X151181I-8268J0D01*
G01D02*
G03X167717I8268J0D01*
G01D02*
G03X151181I-8268J0D01*
G01D02*
G03X167717I8268J0D01*
G01D02*
G03X151181I-8268J0D01*
G01D02*
G03X167717I8268J0D01*
G01D02*
G03X151181I-8268J0D01*
G01D02*
G03X167717I8268J0D01*
G01X151181D02*
G03X167717I8268J0D01*
G01D02*
G03X151181I-8268J0D01*
G01D02*
G03X167717I8268J0D01*
G01D02*
G03X151181I-8268J0D01*
G01X177166Y422047D02*
Y475984D01*
G01X173229Y418110D02*
G03X177166Y422047I0J3937D01*
G01X211024Y437795D02*
G03X194489I-8267J0D01*
G01D02*
G03X211024I8267J0D01*
G01D02*
G03X194489I-8267J0D01*
G01D02*
G03X211024I8267J0D01*
G01D02*
G03X194489I-8267J0D01*
G01D02*
G03X211024I8267J0D01*
G01D02*
G03X194489I-8267J0D01*
G01D02*
G03X211024I8267J0D01*
G01X194489D02*
G03X211024I8267J0D01*
G01D02*
G03X194489I-8267J0D01*
G01D02*
G03X211024I8267J0D01*
G01D02*
G03X194489I-8267J0D01*
G01X188977Y418110D02*
X358268D01*
G01X185040Y422047D02*
G03X188977Y418110I3937J0D01*
G01X185040Y475984D02*
Y422047D01*
G01X167717Y368110D02*
G03X151181I-8268J0D01*
G01X167717D02*
G03X151181I-8268J0D01*
G01X167717D02*
G03X151181I-8268J0D01*
G01X167717D02*
G03X151181I-8268J0D01*
G01X167717D02*
G03X151181I-8268J0D01*
G01X167717D02*
G03X151181I-8268J0D01*
G01X177166Y406299D02*
G03X173229Y410236I-3937J0D01*
G01X211024Y368110D02*
G03X194489I-8267J0D01*
G01X211024D02*
G03X194489I-8267J0D01*
G01X211024D02*
G03X194489I-8267J0D01*
G01X211024D02*
G03X194489I-8267J0D01*
G01X211024D02*
G03X194489I-8267J0D01*
G01X211024D02*
G03X194489I-8267J0D01*
G01X188977Y410236D02*
G03X185040Y406299I0J-3937D01*
G01X358268Y410236D02*
X188977D01*
G01X185040Y506102D02*
G03X177166I-3937J0D01*
G01Y531299D02*
G03X185040I3937J0D01*
G01X177166Y461614D02*
G03X185040I3937J0D01*
G01X196851Y479921D02*
G03Y487795I0J3937D01*
G01X165355D02*
G03Y479921I0J-3937D01*
G01X140158D02*
G03Y487795I0J3937D01*
G01X167717Y507480D02*
G03X151181I-8268J0D01*
G01D02*
G03X167717I8268J0D01*
G01D02*
G03X151181I-8268J0D01*
G01D02*
G03X167717I8268J0D01*
G01D02*
G03X151181I-8268J0D01*
G01D02*
G03X167717I8268J0D01*
G01D02*
G03X151181I-8268J0D01*
G01D02*
G03X167717I8268J0D01*
G01X151181D02*
G03X167717I8268J0D01*
G01D02*
G03X151181I-8268J0D01*
G01D02*
G03X167717I8268J0D01*
G01D02*
G03X151181I-8268J0D01*
G01X177166Y491732D02*
Y545669D01*
G01X173229Y487795D02*
G03X177166Y491732I0J3937D01*
G01X211024Y507480D02*
G03X194489I-8267J0D01*
G01D02*
G03X211024I8267J0D01*
G01D02*
G03X194489I-8267J0D01*
G01D02*
G03X211024I8267J0D01*
G01D02*
G03X194489I-8267J0D01*
G01D02*
G03X211024I8267J0D01*
G01D02*
G03X194489I-8267J0D01*
G01D02*
G03X211024I8267J0D01*
G01X194489D02*
G03X211024I8267J0D01*
G01D02*
G03X194489I-8267J0D01*
G01D02*
G03X211024I8267J0D01*
G01D02*
G03X194489I-8267J0D01*
G01X188977Y487795D02*
X358268D01*
G01X185040Y491732D02*
G03X188977Y487795I3937J0D01*
G01X185040Y545669D02*
Y491732D01*
G01X177166Y475984D02*
G03X173229Y479921I-3937J0D01*
G01X188977D02*
G03X185040Y475984I0J-3937D01*
G01X358268Y479921D02*
X188977D01*
G01X185040Y575787D02*
G03X177166I-3937J0D01*
G01Y600984D02*
G03X185040I3937J0D01*
G01X196851Y549606D02*
G03Y557480I0J3937D01*
G01X165355D02*
G03Y549606I0J-3937D01*
G01X140158D02*
G03Y557480I0J3937D01*
G01X167717Y577165D02*
G03X151181I-8268J0D01*
G01D02*
G03X167717I8268J0D01*
G01D02*
G03X151181I-8268J0D01*
G01D02*
G03X167717I8268J0D01*
G01D02*
G03X151181I-8268J0D01*
G01D02*
G03X167717I8268J0D01*
G01D02*
G03X151181I-8268J0D01*
G01D02*
G03X167717I8268J0D01*
G01X151181D02*
G03X167717I8268J0D01*
G01D02*
G03X151181I-8268J0D01*
G01D02*
G03X167717I8268J0D01*
G01D02*
G03X151181I-8268J0D01*
G01X177166Y561417D02*
Y615354D01*
G01X173229Y557480D02*
G03X177166Y561417I0J3937D01*
G01X211024Y577165D02*
G03X194489I-8267J0D01*
G01D02*
G03X211024I8267J0D01*
G01D02*
G03X194489I-8267J0D01*
G01D02*
G03X211024I8267J0D01*
G01D02*
G03X194489I-8267J0D01*
G01D02*
G03X211024I8267J0D01*
G01D02*
G03X194489I-8267J0D01*
G01D02*
G03X211024I8267J0D01*
G01X194489D02*
G03X211024I8267J0D01*
G01D02*
G03X194489I-8267J0D01*
G01D02*
G03X211024I8267J0D01*
G01D02*
G03X194489I-8267J0D01*
G01X188977Y557480D02*
X358268D01*
G01X185040Y561417D02*
G03X188977Y557480I3937J0D01*
G01X185040Y615354D02*
Y561417D01*
G01X177166Y545669D02*
G03X173229Y549606I-3937J0D01*
G01X188977D02*
G03X185040Y545669I0J-3937D01*
G01X358268Y549606D02*
X188977D01*
G01X185040Y645472D02*
G03X177166I-3937J0D01*
G01Y670669D02*
G03X185040I3937J0D01*
G01X196851Y619291D02*
G03Y627165I0J3937D01*
G01X165355D02*
G03Y619291I0J-3937D01*
G01X140158D02*
G03Y627165I0J3937D01*
G01X167717Y646850D02*
G03X151181I-8268J0D01*
G01D02*
G03X167717I8268J0D01*
G01D02*
G03X151181I-8268J0D01*
G01D02*
G03X167717I8268J0D01*
G01D02*
G03X151181I-8268J0D01*
G01D02*
G03X167717I8268J0D01*
G01D02*
G03X151181I-8268J0D01*
G01D02*
G03X167717I8268J0D01*
G01X151181D02*
G03X167717I8268J0D01*
G01D02*
G03X151181I-8268J0D01*
G01D02*
G03X167717I8268J0D01*
G01D02*
G03X151181I-8268J0D01*
G01X177166Y631102D02*
Y685039D01*
G01X173229Y627165D02*
G03X177166Y631102I0J3937D01*
G01Y685039D02*
G03X173229Y688976I-3937J0D01*
G01X211024Y646850D02*
G03X194489I-8267J0D01*
G01D02*
G03X211024I8267J0D01*
G01D02*
G03X194489I-8267J0D01*
G01D02*
G03X211024I8267J0D01*
G01D02*
G03X194489I-8267J0D01*
G01D02*
G03X211024I8267J0D01*
G01D02*
G03X194489I-8267J0D01*
G01D02*
G03X211024I8267J0D01*
G01X194489D02*
G03X211024I8267J0D01*
G01D02*
G03X194489I-8267J0D01*
G01D02*
G03X211024I8267J0D01*
G01D02*
G03X194489I-8267J0D01*
G01X188977Y627165D02*
X358268D01*
G01X185040Y631102D02*
G03X188977Y627165I3937J0D01*
G01X185040Y685039D02*
Y631102D01*
G01X188977Y688976D02*
G03X185040Y685039I0J-3937D01*
G01X358268Y688976D02*
X188977D01*
G01X177166Y615354D02*
G03X173229Y619291I-3937J0D01*
G01X188977D02*
G03X185040Y615354I0J-3937D01*
G01X358268Y619291D02*
X188977D01*
G01X222048Y0D02*
G03Y-7874I0J-3937D01*
G01D02*
X325197D01*
G01X222048Y69685D02*
G03Y61811I0J-3937D01*
G01Y139370D02*
G03Y131496I0J-3937D01*
G01Y278740D02*
G03Y270866I0J-3937D01*
G01Y209055D02*
G03Y201181I0J-3937D01*
G01Y348425D02*
G03Y340551I0J-3937D01*
G01Y418110D02*
G03Y410236I0J-3937D01*
G01Y487795D02*
G03Y479921I0J-3937D01*
G01Y557480D02*
G03Y549606I0J-3937D01*
G01Y627165D02*
G03Y619291I0J-3937D01*
G01X370079Y18307D02*
G03X362205I-3937J0D01*
G01X350394Y0D02*
G03Y-7874I0J-3937D01*
G01X325197D02*
G03Y0I0J3937D01*
G01X350394Y-7874D02*
X381890D01*
G01X352756Y19685D02*
G03X336221I-8267J0D01*
G01D02*
G03X352756I8268J0D01*
G01D02*
G03X336221I-8267J0D01*
G01D02*
G03X352756I8268J0D01*
G01D02*
G03X336221I-8267J0D01*
G01D02*
G03X352756I8268J0D01*
G01D02*
G03X336221I-8267J0D01*
G01D02*
G03X352756I8268J0D01*
G01X336221D02*
G03X352756I8268J0D01*
G01D02*
G03X336221I-8267J0D01*
G01D02*
G03X352756I8268J0D01*
G01D02*
G03X336221I-8267J0D01*
G01X362205Y3937D02*
Y57874D01*
G01X358268Y0D02*
G03X362205Y3937I0J3937D01*
G01X370079Y87992D02*
G03X362205I-3937J0D01*
G01Y113189D02*
G03X370079I3937J0D01*
G01X362205Y43504D02*
G03X370079I3937J0D01*
G01X350394Y69685D02*
G03Y61811I0J-3937D01*
G01X325197D02*
G03Y69685I0J3937D01*
G01X352756Y89370D02*
G03X336221I-8267J0D01*
G01D02*
G03X352756I8268J0D01*
G01D02*
G03X336221I-8267J0D01*
G01D02*
G03X352756I8268J0D01*
G01D02*
G03X336221I-8267J0D01*
G01D02*
G03X352756I8268J0D01*
G01D02*
G03X336221I-8267J0D01*
G01D02*
G03X352756I8268J0D01*
G01X336221D02*
G03X352756I8268J0D01*
G01D02*
G03X336221I-8267J0D01*
G01D02*
G03X352756I8268J0D01*
G01D02*
G03X336221I-8267J0D01*
G01X362205Y73622D02*
Y127559D01*
G01X358268Y69685D02*
G03X362205Y73622I0J3937D01*
G01Y57874D02*
G03X358268Y61811I-3937J0D01*
G01X370079Y157677D02*
G03X362205I-3937J0D01*
G01Y182874D02*
G03X370079I3937J0D01*
G01X350394Y139370D02*
G03Y131496I0J-3937D01*
G01X325197D02*
G03Y139370I0J3937D01*
G01X352756Y159055D02*
G03X336221I-8267J0D01*
G01D02*
G03X352756I8268J0D01*
G01D02*
G03X336221I-8267J0D01*
G01D02*
G03X352756I8268J0D01*
G01D02*
G03X336221I-8267J0D01*
G01D02*
G03X352756I8268J0D01*
G01D02*
G03X336221I-8267J0D01*
G01D02*
G03X352756I8268J0D01*
G01X336221D02*
G03X352756I8268J0D01*
G01D02*
G03X336221I-8267J0D01*
G01D02*
G03X352756I8268J0D01*
G01D02*
G03X336221I-8267J0D01*
G01X362205Y143307D02*
Y197244D01*
G01X358268Y139370D02*
G03X362205Y143307I0J3937D01*
G01Y127559D02*
G03X358268Y131496I-3937J0D01*
G01X370079Y227362D02*
G03X362205I-3937J0D01*
G01Y252559D02*
G03X370079I3937J0D01*
G01X350394Y278740D02*
G03Y270866I0J-3937D01*
G01X325197D02*
G03Y278740I0J3937D01*
G01X350394Y209055D02*
G03Y201181I0J-3937D01*
G01X325197D02*
G03Y209055I0J3937D01*
G01X358268Y278740D02*
G03X362205Y282677I0J3937D01*
G01X352756Y228740D02*
G03X336221I-8267J0D01*
G01D02*
G03X352756I8268J0D01*
G01D02*
G03X336221I-8267J0D01*
G01D02*
G03X352756I8268J0D01*
G01D02*
G03X336221I-8267J0D01*
G01D02*
G03X352756I8268J0D01*
G01D02*
G03X336221I-8267J0D01*
G01D02*
G03X352756I8268J0D01*
G01X336221D02*
G03X352756I8268J0D01*
G01D02*
G03X336221I-8267J0D01*
G01D02*
G03X352756I8268J0D01*
G01D02*
G03X336221I-8267J0D01*
G01X362205Y212992D02*
Y266929D01*
G01X358268Y209055D02*
G03X362205Y212992I0J3937D01*
G01Y266929D02*
G03X358268Y270866I-3937J0D01*
G01X362205Y197244D02*
G03X358268Y201181I-3937J0D01*
G01X370079Y297047D02*
G03X362205I-3937J0D01*
G01Y322244D02*
G03X370079I3937J0D01*
G01X350394Y348425D02*
G03Y340551I0J-3937D01*
G01X325197D02*
G03Y348425I0J3937D01*
G01X336221Y368110D02*
G03X352756I8268J0D01*
G01X336221D02*
G03X352756I8268J0D01*
G01X336221D02*
G03X352756I8268J0D01*
G01X336221D02*
G03X352756I8268J0D01*
G01X336221D02*
G03X352756I8268J0D01*
G01X336221D02*
G03X352756I8268J0D01*
G01X362205Y352362D02*
Y406299D01*
G01X358268Y348425D02*
G03X362205Y352362I0J3937D01*
G01X352756Y298425D02*
G03X336221I-8267J0D01*
G01D02*
G03X352756I8268J0D01*
G01D02*
G03X336221I-8267J0D01*
G01D02*
G03X352756I8268J0D01*
G01D02*
G03X336221I-8267J0D01*
G01D02*
G03X352756I8268J0D01*
G01D02*
G03X336221I-8267J0D01*
G01D02*
G03X352756I8268J0D01*
G01X336221D02*
G03X352756I8268J0D01*
G01D02*
G03X336221I-8267J0D01*
G01D02*
G03X352756I8268J0D01*
G01D02*
G03X336221I-8267J0D01*
G01X362205Y282677D02*
Y336614D01*
G01D02*
G03X358268Y340551I-3937J0D01*
G01X370079Y436417D02*
G03X362205I-3937J0D01*
G01X370079Y366732D02*
G03X362205I-3937J0D01*
G01Y391929D02*
G03X370079I3937J0D01*
G01X350394Y418110D02*
G03Y410236I0J-3937D01*
G01X325197D02*
G03Y418110I0J3937D01*
G01X352756Y437795D02*
G03X336221I-8267J0D01*
G01D02*
G03X352756I8268J0D01*
G01D02*
G03X336221I-8267J0D01*
G01D02*
G03X352756I8268J0D01*
G01D02*
G03X336221I-8267J0D01*
G01D02*
G03X352756I8268J0D01*
G01D02*
G03X336221I-8267J0D01*
G01D02*
G03X352756I8268J0D01*
G01X336221D02*
G03X352756I8268J0D01*
G01D02*
G03X336221I-8267J0D01*
G01D02*
G03X352756I8268J0D01*
G01D02*
G03X336221I-8267J0D01*
G01X362205Y422047D02*
Y475984D01*
G01X358268Y418110D02*
G03X362205Y422047I0J3937D01*
G01X352756Y368110D02*
G03X336221I-8267J0D01*
G01X352756D02*
G03X336221I-8267J0D01*
G01X352756D02*
G03X336221I-8267J0D01*
G01X352756D02*
G03X336221I-8267J0D01*
G01X352756D02*
G03X336221I-8267J0D01*
G01X352756D02*
G03X336221I-8267J0D01*
G01X362205Y406299D02*
G03X358268Y410236I-3937J0D01*
G01X370079Y506102D02*
G03X362205I-3937J0D01*
G01Y531299D02*
G03X370079I3937J0D01*
G01X362205Y461614D02*
G03X370079I3937J0D01*
G01X350394Y487795D02*
G03Y479921I0J-3937D01*
G01X325197D02*
G03Y487795I0J3937D01*
G01X352756Y507480D02*
G03X336221I-8267J0D01*
G01D02*
G03X352756I8268J0D01*
G01D02*
G03X336221I-8267J0D01*
G01D02*
G03X352756I8268J0D01*
G01D02*
G03X336221I-8267J0D01*
G01D02*
G03X352756I8268J0D01*
G01D02*
G03X336221I-8267J0D01*
G01D02*
G03X352756I8268J0D01*
G01X336221D02*
G03X352756I8268J0D01*
G01D02*
G03X336221I-8267J0D01*
G01D02*
G03X352756I8268J0D01*
G01D02*
G03X336221I-8267J0D01*
G01X362205Y491732D02*
Y545669D01*
G01X358268Y487795D02*
G03X362205Y491732I0J3937D01*
G01Y475984D02*
G03X358268Y479921I-3937J0D01*
G01X370079Y575787D02*
G03X362205I-3937J0D01*
G01Y600984D02*
G03X370079I3937J0D01*
G01X350394Y557480D02*
G03Y549606I0J-3937D01*
G01X325197D02*
G03Y557480I0J3937D01*
G01X352756Y577165D02*
G03X336221I-8267J0D01*
G01D02*
G03X352756I8268J0D01*
G01D02*
G03X336221I-8267J0D01*
G01D02*
G03X352756I8268J0D01*
G01D02*
G03X336221I-8267J0D01*
G01D02*
G03X352756I8268J0D01*
G01D02*
G03X336221I-8267J0D01*
G01D02*
G03X352756I8268J0D01*
G01X336221D02*
G03X352756I8268J0D01*
G01D02*
G03X336221I-8267J0D01*
G01D02*
G03X352756I8268J0D01*
G01D02*
G03X336221I-8267J0D01*
G01X362205Y561417D02*
Y615354D01*
G01X358268Y557480D02*
G03X362205Y561417I0J3937D01*
G01Y545669D02*
G03X358268Y549606I-3937J0D01*
G01X370079Y645472D02*
G03X362205I-3937J0D01*
G01Y670669D02*
G03X370079I3937J0D01*
G01X350394Y627165D02*
G03Y619291I0J-3937D01*
G01X325197D02*
G03Y627165I0J3937D01*
G01X352756Y646850D02*
G03X336221I-8267J0D01*
G01D02*
G03X352756I8268J0D01*
G01D02*
G03X336221I-8267J0D01*
G01D02*
G03X352756I8268J0D01*
G01D02*
G03X336221I-8267J0D01*
G01D02*
G03X352756I8268J0D01*
G01D02*
G03X336221I-8267J0D01*
G01D02*
G03X352756I8268J0D01*
G01X336221D02*
G03X352756I8268J0D01*
G01D02*
G03X336221I-8267J0D01*
G01D02*
G03X352756I8268J0D01*
G01D02*
G03X336221I-8267J0D01*
G01X362205Y631102D02*
Y685039D01*
G01X358268Y627165D02*
G03X362205Y631102I0J3937D01*
G01Y685039D02*
G03X358268Y688976I-3937J0D01*
G01X362205Y615354D02*
G03X358268Y619291I-3937J0D01*
G01X407087Y0D02*
G03Y-7874I0J-3937D01*
G01X381890D02*
G03Y0I0J3937D01*
G01X407087Y-7874D02*
X510237D01*
G01X396063Y19685D02*
G03X379528I-8268J0D01*
G01D02*
G03X396063I8267J0D01*
G01D02*
G03X379528I-8268J0D01*
G01D02*
G03X396063I8267J0D01*
G01D02*
G03X379528I-8268J0D01*
G01D02*
G03X396063I8267J0D01*
G01D02*
G03X379528I-8268J0D01*
G01D02*
G03X396063I8267J0D01*
G01X379528D02*
G03X396063I8267J0D01*
G01D02*
G03X379528I-8268J0D01*
G01D02*
G03X396063I8267J0D01*
G01D02*
G03X379528I-8268J0D01*
G01X374016Y0D02*
X543307D01*
G01X370079Y3937D02*
G03X374016Y0I3937J0D01*
G01X370079Y57874D02*
Y3937D01*
G01X407087Y69685D02*
G03Y61811I0J-3937D01*
G01X381890D02*
G03Y69685I0J3937D01*
G01X396063Y89370D02*
G03X379528I-8268J0D01*
G01D02*
G03X396063I8267J0D01*
G01D02*
G03X379528I-8268J0D01*
G01D02*
G03X396063I8267J0D01*
G01D02*
G03X379528I-8268J0D01*
G01D02*
G03X396063I8267J0D01*
G01D02*
G03X379528I-8268J0D01*
G01D02*
G03X396063I8267J0D01*
G01X379528D02*
G03X396063I8267J0D01*
G01D02*
G03X379528I-8268J0D01*
G01D02*
G03X396063I8267J0D01*
G01D02*
G03X379528I-8268J0D01*
G01X374016Y69685D02*
X543307D01*
G01X370079Y73622D02*
G03X374016Y69685I3937J0D01*
G01X370079Y127559D02*
Y73622D01*
G01X374016Y61811D02*
G03X370079Y57874I0J-3937D01*
G01X543307Y61811D02*
X374016D01*
G01X407087Y139370D02*
G03Y131496I0J-3937D01*
G01X381890D02*
G03Y139370I0J3937D01*
G01X396063Y159055D02*
G03X379528I-8268J0D01*
G01D02*
G03X396063I8267J0D01*
G01D02*
G03X379528I-8268J0D01*
G01D02*
G03X396063I8267J0D01*
G01D02*
G03X379528I-8268J0D01*
G01D02*
G03X396063I8267J0D01*
G01D02*
G03X379528I-8268J0D01*
G01D02*
G03X396063I8267J0D01*
G01X379528D02*
G03X396063I8267J0D01*
G01D02*
G03X379528I-8268J0D01*
G01D02*
G03X396063I8267J0D01*
G01D02*
G03X379528I-8268J0D01*
G01X374016Y139370D02*
X543307D01*
G01X370079Y143307D02*
G03X374016Y139370I3937J0D01*
G01X370079Y197244D02*
Y143307D01*
G01X374016Y131496D02*
G03X370079Y127559I0J-3937D01*
G01X543307Y131496D02*
X374016D01*
G01X407087Y278740D02*
G03Y270866I0J-3937D01*
G01X381890D02*
G03Y278740I0J3937D01*
G01X407087Y209055D02*
G03Y201181I0J-3937D01*
G01X381890D02*
G03Y209055I0J3937D01*
G01X374016Y278740D02*
X543307D01*
G01X370079Y282677D02*
G03X374016Y278740I3937J0D01*
G01X396063Y228740D02*
G03X379528I-8268J0D01*
G01D02*
G03X396063I8267J0D01*
G01D02*
G03X379528I-8268J0D01*
G01D02*
G03X396063I8267J0D01*
G01D02*
G03X379528I-8268J0D01*
G01D02*
G03X396063I8267J0D01*
G01D02*
G03X379528I-8268J0D01*
G01D02*
G03X396063I8267J0D01*
G01X379528D02*
G03X396063I8267J0D01*
G01D02*
G03X379528I-8268J0D01*
G01D02*
G03X396063I8267J0D01*
G01D02*
G03X379528I-8268J0D01*
G01X374016Y209055D02*
X543307D01*
G01X370079Y212992D02*
G03X374016Y209055I3937J0D01*
G01X370079Y266929D02*
Y212992D01*
G01X374016Y270866D02*
G03X370079Y266929I0J-3937D01*
G01X543307Y270866D02*
X374016D01*
G01Y201181D02*
G03X370079Y197244I0J-3937D01*
G01X543307Y201181D02*
X374016D01*
G01X407087Y348425D02*
G03Y340551I0J-3937D01*
G01X381890D02*
G03Y348425I0J3937D01*
G01X379528Y368110D02*
G03X396063I8267J0D01*
G01X379528D02*
G03X396063I8267J0D01*
G01X379528D02*
G03X396063I8267J0D01*
G01X379528D02*
G03X396063I8267J0D01*
G01X379528D02*
G03X396063I8267J0D01*
G01X379528D02*
G03X396063I8267J0D01*
G01X374016Y348425D02*
X543307D01*
G01X370079Y352362D02*
G03X374016Y348425I3937J0D01*
G01X370079Y406299D02*
Y352362D01*
G01X396063Y298425D02*
G03X379528I-8268J0D01*
G01D02*
G03X396063I8267J0D01*
G01D02*
G03X379528I-8268J0D01*
G01D02*
G03X396063I8267J0D01*
G01D02*
G03X379528I-8268J0D01*
G01D02*
G03X396063I8267J0D01*
G01D02*
G03X379528I-8268J0D01*
G01D02*
G03X396063I8267J0D01*
G01X379528D02*
G03X396063I8267J0D01*
G01D02*
G03X379528I-8268J0D01*
G01D02*
G03X396063I8267J0D01*
G01D02*
G03X379528I-8268J0D01*
G01X370079Y336614D02*
Y282677D01*
G01X374016Y340551D02*
G03X370079Y336614I0J-3937D01*
G01X543307Y340551D02*
X374016D01*
G01X407087Y418110D02*
G03Y410236I0J-3937D01*
G01X381890D02*
G03Y418110I0J3937D01*
G01X396063Y437795D02*
G03X379528I-8268J0D01*
G01D02*
G03X396063I8267J0D01*
G01D02*
G03X379528I-8268J0D01*
G01D02*
G03X396063I8267J0D01*
G01D02*
G03X379528I-8268J0D01*
G01D02*
G03X396063I8267J0D01*
G01D02*
G03X379528I-8268J0D01*
G01D02*
G03X396063I8267J0D01*
G01X379528D02*
G03X396063I8267J0D01*
G01D02*
G03X379528I-8268J0D01*
G01D02*
G03X396063I8267J0D01*
G01D02*
G03X379528I-8268J0D01*
G01X374016Y418110D02*
X543307D01*
G01X370079Y422047D02*
G03X374016Y418110I3937J0D01*
G01X370079Y475984D02*
Y422047D01*
G01X396063Y368110D02*
G03X379528I-8268J0D01*
G01X396063D02*
G03X379528I-8268J0D01*
G01X396063D02*
G03X379528I-8268J0D01*
G01X396063D02*
G03X379528I-8268J0D01*
G01X396063D02*
G03X379528I-8268J0D01*
G01X396063D02*
G03X379528I-8268J0D01*
G01X374016Y410236D02*
G03X370079Y406299I0J-3937D01*
G01X543307Y410236D02*
X374016D01*
G01X407087Y487795D02*
G03Y479921I0J-3937D01*
G01X381890D02*
G03Y487795I0J3937D01*
G01X396063Y507480D02*
G03X379528I-8268J0D01*
G01D02*
G03X396063I8267J0D01*
G01D02*
G03X379528I-8268J0D01*
G01D02*
G03X396063I8267J0D01*
G01D02*
G03X379528I-8268J0D01*
G01D02*
G03X396063I8267J0D01*
G01D02*
G03X379528I-8268J0D01*
G01D02*
G03X396063I8267J0D01*
G01X379528D02*
G03X396063I8267J0D01*
G01D02*
G03X379528I-8268J0D01*
G01D02*
G03X396063I8267J0D01*
G01D02*
G03X379528I-8268J0D01*
G01X374016Y487795D02*
X543307D01*
G01X370079Y491732D02*
G03X374016Y487795I3937J0D01*
G01X370079Y545669D02*
Y491732D01*
G01X374016Y479921D02*
G03X370079Y475984I0J-3937D01*
G01X543307Y479921D02*
X374016D01*
G01X407087Y557480D02*
G03Y549606I0J-3937D01*
G01X381890D02*
G03Y557480I0J3937D01*
G01X396063Y577165D02*
G03X379528I-8268J0D01*
G01D02*
G03X396063I8267J0D01*
G01D02*
G03X379528I-8268J0D01*
G01D02*
G03X396063I8267J0D01*
G01D02*
G03X379528I-8268J0D01*
G01D02*
G03X396063I8267J0D01*
G01D02*
G03X379528I-8268J0D01*
G01D02*
G03X396063I8267J0D01*
G01X379528D02*
G03X396063I8267J0D01*
G01D02*
G03X379528I-8268J0D01*
G01D02*
G03X396063I8267J0D01*
G01D02*
G03X379528I-8268J0D01*
G01X374016Y557480D02*
X543307D01*
G01X370079Y561417D02*
G03X374016Y557480I3937J0D01*
G01X370079Y615354D02*
Y561417D01*
G01X374016Y549606D02*
G03X370079Y545669I0J-3937D01*
G01X543307Y549606D02*
X374016D01*
G01X407087Y627165D02*
G03Y619291I0J-3937D01*
G01X381890D02*
G03Y627165I0J3937D01*
G01X396063Y646850D02*
G03X379528I-8268J0D01*
G01D02*
G03X396063I8267J0D01*
G01D02*
G03X379528I-8268J0D01*
G01D02*
G03X396063I8267J0D01*
G01D02*
G03X379528I-8268J0D01*
G01D02*
G03X396063I8267J0D01*
G01D02*
G03X379528I-8268J0D01*
G01D02*
G03X396063I8267J0D01*
G01X379528D02*
G03X396063I8267J0D01*
G01D02*
G03X379528I-8268J0D01*
G01D02*
G03X396063I8267J0D01*
G01D02*
G03X379528I-8268J0D01*
G01X374016Y627165D02*
X543307D01*
G01X370079Y631102D02*
G03X374016Y627165I3937J0D01*
G01X370079Y685039D02*
Y631102D01*
G01X374016Y688976D02*
G03X370079Y685039I0J-3937D01*
G01X543307Y688976D02*
X374016D01*
G01Y619291D02*
G03X370079Y615354I0J-3937D01*
G01X543307Y619291D02*
X374016D01*
G01X510237Y-7874D02*
G03Y0I0J3937D01*
G01X537796Y19685D02*
G03X521260I-8268J0D01*
G01D02*
G03X537796I8268J0D01*
G01D02*
G03X521260I-8268J0D01*
G01D02*
G03X537796I8268J0D01*
G01D02*
G03X521260I-8268J0D01*
G01D02*
G03X537796I8268J0D01*
G01D02*
G03X521260I-8268J0D01*
G01D02*
G03X537796I8268J0D01*
G01X521260D02*
G03X537796I8268J0D01*
G01D02*
G03X521260I-8268J0D01*
G01D02*
G03X537796I8268J0D01*
G01D02*
G03X521260I-8268J0D01*
G01X510237Y61811D02*
G03Y69685I0J3937D01*
G01X537796Y89370D02*
G03X521260I-8268J0D01*
G01D02*
G03X537796I8268J0D01*
G01D02*
G03X521260I-8268J0D01*
G01D02*
G03X537796I8268J0D01*
G01D02*
G03X521260I-8268J0D01*
G01D02*
G03X537796I8268J0D01*
G01D02*
G03X521260I-8268J0D01*
G01D02*
G03X537796I8268J0D01*
G01X521260D02*
G03X537796I8268J0D01*
G01D02*
G03X521260I-8268J0D01*
G01D02*
G03X537796I8268J0D01*
G01D02*
G03X521260I-8268J0D01*
G01X510237Y131496D02*
G03Y139370I0J3937D01*
G01X537796Y159055D02*
G03X521260I-8268J0D01*
G01D02*
G03X537796I8268J0D01*
G01D02*
G03X521260I-8268J0D01*
G01D02*
G03X537796I8268J0D01*
G01D02*
G03X521260I-8268J0D01*
G01D02*
G03X537796I8268J0D01*
G01D02*
G03X521260I-8268J0D01*
G01D02*
G03X537796I8268J0D01*
G01X521260D02*
G03X537796I8268J0D01*
G01D02*
G03X521260I-8268J0D01*
G01D02*
G03X537796I8268J0D01*
G01D02*
G03X521260I-8268J0D01*
G01X510237Y270866D02*
G03Y278740I0J3937D01*
G01Y201181D02*
G03Y209055I0J3937D01*
G01X537796Y228740D02*
G03X521260I-8268J0D01*
G01D02*
G03X537796I8268J0D01*
G01D02*
G03X521260I-8268J0D01*
G01D02*
G03X537796I8268J0D01*
G01D02*
G03X521260I-8268J0D01*
G01D02*
G03X537796I8268J0D01*
G01D02*
G03X521260I-8268J0D01*
G01D02*
G03X537796I8268J0D01*
G01X521260D02*
G03X537796I8268J0D01*
G01D02*
G03X521260I-8268J0D01*
G01D02*
G03X537796I8268J0D01*
G01D02*
G03X521260I-8268J0D01*
G01X510237Y340551D02*
G03Y348425I0J3937D01*
G01X521260Y368110D02*
G03X537796I8268J0D01*
G01X521260D02*
G03X537796I8268J0D01*
G01X521260D02*
G03X537796I8268J0D01*
G01X521260D02*
G03X537796I8268J0D01*
G01X521260D02*
G03X537796I8268J0D01*
G01X521260D02*
G03X537796I8268J0D01*
G01Y298425D02*
G03X521260I-8268J0D01*
G01D02*
G03X537796I8268J0D01*
G01D02*
G03X521260I-8268J0D01*
G01D02*
G03X537796I8268J0D01*
G01D02*
G03X521260I-8268J0D01*
G01D02*
G03X537796I8268J0D01*
G01D02*
G03X521260I-8268J0D01*
G01D02*
G03X537796I8268J0D01*
G01X521260D02*
G03X537796I8268J0D01*
G01D02*
G03X521260I-8268J0D01*
G01D02*
G03X537796I8268J0D01*
G01D02*
G03X521260I-8268J0D01*
G01X510237Y410236D02*
G03Y418110I0J3937D01*
G01X537796Y437795D02*
G03X521260I-8268J0D01*
G01D02*
G03X537796I8268J0D01*
G01D02*
G03X521260I-8268J0D01*
G01D02*
G03X537796I8268J0D01*
G01D02*
G03X521260I-8268J0D01*
G01D02*
G03X537796I8268J0D01*
G01D02*
G03X521260I-8268J0D01*
G01D02*
G03X537796I8268J0D01*
G01X521260D02*
G03X537796I8268J0D01*
G01D02*
G03X521260I-8268J0D01*
G01D02*
G03X537796I8268J0D01*
G01D02*
G03X521260I-8268J0D01*
G01X537796Y368110D02*
G03X521260I-8268J0D01*
G01X537796D02*
G03X521260I-8268J0D01*
G01X537796D02*
G03X521260I-8268J0D01*
G01X537796D02*
G03X521260I-8268J0D01*
G01X537796D02*
G03X521260I-8268J0D01*
G01X537796D02*
G03X521260I-8268J0D01*
G01X510237Y479921D02*
G03Y487795I0J3937D01*
G01X537796Y507480D02*
G03X521260I-8268J0D01*
G01D02*
G03X537796I8268J0D01*
G01D02*
G03X521260I-8268J0D01*
G01D02*
G03X537796I8268J0D01*
G01D02*
G03X521260I-8268J0D01*
G01D02*
G03X537796I8268J0D01*
G01D02*
G03X521260I-8268J0D01*
G01D02*
G03X537796I8268J0D01*
G01X521260D02*
G03X537796I8268J0D01*
G01D02*
G03X521260I-8268J0D01*
G01D02*
G03X537796I8268J0D01*
G01D02*
G03X521260I-8268J0D01*
G01X510237Y549606D02*
G03Y557480I0J3937D01*
G01X537796Y577165D02*
G03X521260I-8268J0D01*
G01D02*
G03X537796I8268J0D01*
G01D02*
G03X521260I-8268J0D01*
G01D02*
G03X537796I8268J0D01*
G01D02*
G03X521260I-8268J0D01*
G01D02*
G03X537796I8268J0D01*
G01D02*
G03X521260I-8268J0D01*
G01D02*
G03X537796I8268J0D01*
G01X521260D02*
G03X537796I8268J0D01*
G01D02*
G03X521260I-8268J0D01*
G01D02*
G03X537796I8268J0D01*
G01D02*
G03X521260I-8268J0D01*
G01X510237Y619291D02*
G03Y627165I0J3937D01*
G01X537796Y646850D02*
G03X521260I-8268J0D01*
G01D02*
G03X537796I8268J0D01*
G01D02*
G03X521260I-8268J0D01*
G01D02*
G03X537796I8268J0D01*
G01D02*
G03X521260I-8268J0D01*
G01D02*
G03X537796I8268J0D01*
G01D02*
G03X521260I-8268J0D01*
G01D02*
G03X537796I8268J0D01*
G01X521260D02*
G03X537796I8268J0D01*
G01D02*
G03X521260I-8268J0D01*
G01D02*
G03X537796I8268J0D01*
G01D02*
G03X521260I-8268J0D01*
G01X539370Y-19685D02*
G03X547244Y-11811I0J7874D01*
G01X535433Y0D02*
G03Y-7874I0J-3937D01*
G01X547244D02*
Y-11811D01*
G01X535433Y-7874D02*
X547244D01*
G01Y3937D02*
Y57874D01*
G01X543307Y0D02*
G03X547244Y3937I0J3937D01*
G01X535433Y69685D02*
G03Y61811I0J-3937D01*
G01X547244Y73622D02*
Y127559D01*
G01X543307Y69685D02*
G03X547244Y73622I0J3937D01*
G01Y57874D02*
G03X543307Y61811I-3937J0D01*
G01X535433Y139370D02*
G03Y131496I0J-3937D01*
G01X547244Y143307D02*
Y197244D01*
G01X543307Y139370D02*
G03X547244Y143307I0J3937D01*
G01Y127559D02*
G03X543307Y131496I-3937J0D01*
G01X535433Y278740D02*
G03Y270866I0J-3937D01*
G01Y209055D02*
G03Y201181I0J-3937D01*
G01X543307Y278740D02*
G03X547244Y282677I0J3937D01*
G01Y212992D02*
Y266929D01*
G01X543307Y209055D02*
G03X547244Y212992I0J3937D01*
G01Y266929D02*
G03X543307Y270866I-3937J0D01*
G01X547244Y197244D02*
G03X543307Y201181I-3937J0D01*
G01X535433Y348425D02*
G03Y340551I0J-3937D01*
G01X547244Y352362D02*
Y406299D01*
G01X543307Y348425D02*
G03X547244Y352362I0J3937D01*
G01Y282677D02*
Y336614D01*
G01D02*
G03X543307Y340551I-3937J0D01*
G01X535433Y418110D02*
G03Y410236I0J-3937D01*
G01X547244Y422047D02*
Y475984D01*
G01X543307Y418110D02*
G03X547244Y422047I0J3937D01*
G01Y406299D02*
G03X543307Y410236I-3937J0D01*
G01X535433Y487795D02*
G03Y479921I0J-3937D01*
G01X547244Y491732D02*
Y545669D01*
G01X543307Y487795D02*
G03X547244Y491732I0J3937D01*
G01Y475984D02*
G03X543307Y479921I-3937J0D01*
G01X535433Y557480D02*
G03Y549606I0J-3937D01*
G01X547244Y561417D02*
Y615354D01*
G01X543307Y557480D02*
G03X547244Y561417I0J3937D01*
G01Y545669D02*
G03X543307Y549606I-3937J0D01*
G01X535433Y627165D02*
G03Y619291I0J-3937D01*
G01X547244Y631102D02*
Y685039D01*
G01X543307Y627165D02*
G03X547244Y631102I0J3937D01*
G01Y685039D02*
G03X543307Y688976I-3937J0D01*
G01X547244Y615354D02*
G03X543307Y619291I-3937J0D01*
G54D12*
G01X103700Y36400D02*
X104568Y35532D01*
G01D02*
X107579D01*
G01X115453Y52264D02*
X111800D01*
G01X111700Y39600D02*
Y36600D01*
G01D02*
X112768Y35532D01*
G01D02*
X115453D01*
G01X96000Y55600D02*
Y53500D01*
G01D02*
X97236Y52264D01*
G01D02*
X99705D01*
G01X39300Y35500D02*
X47200Y43400D01*
G01D02*
Y47067D01*
G01X119500Y33900D02*
X121132Y35532D01*
G01D02*
X123327D01*
G01X131201Y52264D02*
X127500D01*
G01Y37000D02*
X128968Y35532D01*
G01D02*
X131201D01*
M02*
